FILE_TYPE = MACRO_DRAWING;
SET COLOR_WIRE YELLOW;
SET COLOR_PROP ORANGE;
SET COLOR_DOT WHITE;
SET COLOR_ARC YELLOW;
SET COLOR_BODY GREEN;
SET COLOR_NOTE PURPLE;
SET PROP_DISPLAY VALUE;
SET PAGE_NUMBER P22;
FORCEADD OFFPAGE..2
R 2
(-1025 -400);
FORCEPROP 2 LAST $XR1 87 
J 0
(-1369 -400);
DISPLAY 0.638298 (-1369 -400);
PAINT MONO (-1369 -400);
FORCEPROP 2 LAST $XR0 86 
J 0
(-1279 -400);
DISPLAY 0.638298 (-1279 -400);
PAINT MONO (-1279 -400);
FORCEPROP 2 LAST CDS_LIB standard
J 0
(-1025 -400);
PAINT MONO (-1025 -400);
DISPLAY INVISIBLE (-1025 -400);
FORCEPROP 1 LAST OFFPAGE TRUE
J 2
(-1350 -525);
DISPLAY 0.872340 (-1350 -525);
DISPLAY INVISIBLE (-1350 -525);
FORCEPROP 1 LAST COMMENT_BODY TRUE
J 2
(-980 -495);
DISPLAY 0.872340 (-980 -495);
PAINT GREEN (-980 -495);
DISPLAY INVISIBLE (-980 -495);
FORCEPROP 2 LAST PATH I1
J 0
(-975 -325);
DISPLAY 1.021277 (-975 -325);
DISPLAY INVISIBLE (-975 -325);
FORCEADD TAP..1
R 2
(0 -325);
FORCEPROP 3 LASTPIN (50 -325) SIG_NAME M_C_CPU0_SB_CB<0>
J 0
(60 -315);
DISPLAY 0.659574 (60 -315);
PAINT MONO (60 -315);
DISPLAY INVISIBLE (60 -315);
FORCEPROP 1 LASTPIN (50 -325) BN 0
J 2
(62 -317);
DISPLAY 0.680851 (62 -317);
PAINT GREEN (62 -317);
FORCEPROP 2 LAST CDS_LIB standard
J 0
(0 -325);
DISPLAY INVISIBLE (0 -325);
FORCEPROP 1 LAST BODY_TYPE PLUMBING
J 2
(0 -275);
DISPLAY 0.872340 (0 -275);
PAINT GREEN (0 -275);
DISPLAY INVISIBLE (0 -275);
FORCEPROP 1 LAST HDL_TAP TRUE
J 2
(-325 -450);
DISPLAY 0.872340 (-325 -450);
DISPLAY INVISIBLE (-325 -450);
FORCEPROP 1 LAST PATH I10
J 2
(2 -325);
DISPLAY 0.872340 (2 -325);
PAINT GREEN (2 -325);
DISPLAY INVISIBLE (2 -325);
FORCEADD TAP..1
(3425 175);
FORCEPROP 3 LASTPIN (3375 175) SIG_NAME M_C_CPU0_SA_CS_N<0>
J 0
(3385 185);
DISPLAY 0.659574 (3385 185);
PAINT MONO (3385 185);
DISPLAY INVISIBLE (3385 185);
FORCEPROP 1 LASTPIN (3375 175) BN 0
J 0
(3363 183);
DISPLAY 0.680851 (3363 183);
PAINT GREEN (3363 183);
FORCEPROP 2 LAST CDS_LIB standard
J 0
(3425 175);
DISPLAY INVISIBLE (3425 175);
FORCEPROP 1 LAST BODY_TYPE PLUMBING
J 0
(3425 225);
DISPLAY 0.872340 (3425 225);
PAINT GREEN (3425 225);
DISPLAY INVISIBLE (3425 225);
FORCEPROP 1 LAST HDL_TAP TRUE
J 0
(3750 50);
DISPLAY 0.872340 (3750 50);
DISPLAY INVISIBLE (3750 50);
FORCEPROP 1 LAST PATH I100
J 0
(3423 175);
DISPLAY 0.872340 (3423 175);
PAINT GREEN (3423 175);
DISPLAY INVISIBLE (3423 175);
FORCEADD TAP..1
(3425 275);
FORCEPROP 3 LASTPIN (3375 275) SIG_NAME M_C_CPU0_SA_CS_N<2>
J 0
(3385 285);
DISPLAY 0.659574 (3385 285);
PAINT MONO (3385 285);
DISPLAY INVISIBLE (3385 285);
FORCEPROP 1 LASTPIN (3375 275) BN 2
J 0
(3363 283);
DISPLAY 0.680851 (3363 283);
PAINT GREEN (3363 283);
FORCEPROP 2 LAST CDS_LIB standard
J 0
(3425 275);
DISPLAY INVISIBLE (3425 275);
FORCEPROP 1 LAST BODY_TYPE PLUMBING
J 0
(3425 325);
DISPLAY 0.872340 (3425 325);
PAINT GREEN (3425 325);
DISPLAY INVISIBLE (3425 325);
FORCEPROP 1 LAST HDL_TAP TRUE
J 0
(3750 150);
DISPLAY 0.872340 (3750 150);
DISPLAY INVISIBLE (3750 150);
FORCEPROP 1 LAST PATH I101
J 0
(3423 275);
DISPLAY 0.872340 (3423 275);
PAINT GREEN (3423 275);
DISPLAY INVISIBLE (3423 275);
FORCEADD TAP..1
(3425 225);
FORCEPROP 3 LASTPIN (3375 225) SIG_NAME M_C_CPU0_SA_CS_N<1>
J 0
(3385 235);
DISPLAY 0.659574 (3385 235);
PAINT MONO (3385 235);
DISPLAY INVISIBLE (3385 235);
FORCEPROP 1 LASTPIN (3375 225) BN 1
J 0
(3363 233);
DISPLAY 0.680851 (3363 233);
PAINT GREEN (3363 233);
FORCEPROP 2 LAST CDS_LIB standard
J 0
(3425 225);
DISPLAY INVISIBLE (3425 225);
FORCEPROP 1 LAST BODY_TYPE PLUMBING
J 0
(3425 275);
DISPLAY 0.872340 (3425 275);
PAINT GREEN (3425 275);
DISPLAY INVISIBLE (3425 275);
FORCEPROP 1 LAST HDL_TAP TRUE
J 0
(3750 100);
DISPLAY 0.872340 (3750 100);
DISPLAY INVISIBLE (3750 100);
FORCEPROP 1 LAST PATH I102
J 0
(3423 225);
DISPLAY 0.872340 (3423 225);
PAINT GREEN (3423 225);
DISPLAY INVISIBLE (3423 225);
FORCEADD TAP..1
(3425 325);
FORCEPROP 3 LASTPIN (3375 325) SIG_NAME M_C_CPU0_SA_CS_N<3>
J 0
(3385 335);
DISPLAY 0.659574 (3385 335);
PAINT MONO (3385 335);
DISPLAY INVISIBLE (3385 335);
FORCEPROP 1 LASTPIN (3375 325) BN 3
J 0
(3363 333);
DISPLAY 0.680851 (3363 333);
PAINT GREEN (3363 333);
FORCEPROP 2 LAST CDS_LIB standard
J 0
(3425 325);
DISPLAY INVISIBLE (3425 325);
FORCEPROP 1 LAST BODY_TYPE PLUMBING
J 0
(3425 375);
DISPLAY 0.872340 (3425 375);
PAINT GREEN (3425 375);
DISPLAY INVISIBLE (3425 375);
FORCEPROP 1 LAST HDL_TAP TRUE
J 0
(3750 200);
DISPLAY 0.872340 (3750 200);
DISPLAY INVISIBLE (3750 200);
FORCEPROP 1 LAST PATH I103
J 0
(3423 325);
DISPLAY 0.872340 (3423 325);
PAINT GREEN (3423 325);
DISPLAY INVISIBLE (3423 325);
FORCEADD TAP..1
(3425 575);
FORCEPROP 3 LASTPIN (3375 575) SIG_NAME M_C_CPU0_SB_CA<1>
J 0
(3385 585);
DISPLAY 0.659574 (3385 585);
PAINT MONO (3385 585);
DISPLAY INVISIBLE (3385 585);
FORCEPROP 1 LASTPIN (3375 575) BN 1
J 0
(3363 583);
DISPLAY 0.680851 (3363 583);
PAINT GREEN (3363 583);
FORCEPROP 2 LAST CDS_LIB standard
J 0
(3425 575);
DISPLAY INVISIBLE (3425 575);
FORCEPROP 1 LAST BODY_TYPE PLUMBING
J 0
(3425 625);
DISPLAY 0.872340 (3425 625);
PAINT GREEN (3425 625);
DISPLAY INVISIBLE (3425 625);
FORCEPROP 1 LAST HDL_TAP TRUE
J 0
(3750 450);
DISPLAY 0.872340 (3750 450);
DISPLAY INVISIBLE (3750 450);
FORCEPROP 1 LAST PATH I104
J 0
(3423 575);
DISPLAY 0.872340 (3423 575);
PAINT GREEN (3423 575);
DISPLAY INVISIBLE (3423 575);
FORCEADD TAP..1
(3425 525);
FORCEPROP 3 LASTPIN (3375 525) SIG_NAME M_C_CPU0_SB_CA<0>
J 0
(3385 535);
DISPLAY 0.659574 (3385 535);
PAINT MONO (3385 535);
DISPLAY INVISIBLE (3385 535);
FORCEPROP 1 LASTPIN (3375 525) BN 0
J 0
(3363 533);
DISPLAY 0.680851 (3363 533);
PAINT GREEN (3363 533);
FORCEPROP 2 LAST CDS_LIB standard
J 0
(3425 525);
DISPLAY INVISIBLE (3425 525);
FORCEPROP 1 LAST BODY_TYPE PLUMBING
J 0
(3425 575);
DISPLAY 0.872340 (3425 575);
PAINT GREEN (3425 575);
DISPLAY INVISIBLE (3425 575);
FORCEPROP 1 LAST HDL_TAP TRUE
J 0
(3750 400);
DISPLAY 0.872340 (3750 400);
DISPLAY INVISIBLE (3750 400);
FORCEPROP 1 LAST PATH I105
J 0
(3423 525);
DISPLAY 0.872340 (3423 525);
PAINT GREEN (3423 525);
DISPLAY INVISIBLE (3423 525);
FORCEADD TAP..1
(3425 625);
FORCEPROP 3 LASTPIN (3375 625) SIG_NAME M_C_CPU0_SB_CA<2>
J 0
(3385 635);
DISPLAY 0.659574 (3385 635);
PAINT MONO (3385 635);
DISPLAY INVISIBLE (3385 635);
FORCEPROP 1 LASTPIN (3375 625) BN 2
J 0
(3363 633);
DISPLAY 0.680851 (3363 633);
PAINT GREEN (3363 633);
FORCEPROP 2 LAST CDS_LIB standard
J 0
(3425 625);
DISPLAY INVISIBLE (3425 625);
FORCEPROP 1 LAST BODY_TYPE PLUMBING
J 0
(3425 675);
DISPLAY 0.872340 (3425 675);
PAINT GREEN (3425 675);
DISPLAY INVISIBLE (3425 675);
FORCEPROP 1 LAST HDL_TAP TRUE
J 0
(3750 500);
DISPLAY 0.872340 (3750 500);
DISPLAY INVISIBLE (3750 500);
FORCEPROP 1 LAST PATH I106
J 0
(3423 625);
DISPLAY 0.872340 (3423 625);
PAINT GREEN (3423 625);
DISPLAY INVISIBLE (3423 625);
FORCEADD TAP..1
(3425 825);
FORCEPROP 3 LASTPIN (3375 825) SIG_NAME M_C_CPU0_SB_CA<6>
J 0
(3385 835);
DISPLAY 0.659574 (3385 835);
PAINT MONO (3385 835);
DISPLAY INVISIBLE (3385 835);
FORCEPROP 1 LASTPIN (3375 825) BN 6
J 0
(3363 833);
DISPLAY 0.680851 (3363 833);
PAINT GREEN (3363 833);
FORCEPROP 2 LAST CDS_LIB standard
J 0
(3425 825);
DISPLAY INVISIBLE (3425 825);
FORCEPROP 1 LAST BODY_TYPE PLUMBING
J 0
(3425 875);
DISPLAY 0.872340 (3425 875);
PAINT GREEN (3425 875);
DISPLAY INVISIBLE (3425 875);
FORCEPROP 1 LAST HDL_TAP TRUE
J 0
(3750 700);
DISPLAY 0.872340 (3750 700);
DISPLAY INVISIBLE (3750 700);
FORCEPROP 1 LAST PATH I107
J 0
(3423 825);
DISPLAY 0.872340 (3423 825);
PAINT GREEN (3423 825);
DISPLAY INVISIBLE (3423 825);
FORCEADD TAP..1
(3425 775);
FORCEPROP 3 LASTPIN (3375 775) SIG_NAME M_C_CPU0_SB_CA<5>
J 0
(3385 785);
DISPLAY 0.659574 (3385 785);
PAINT MONO (3385 785);
DISPLAY INVISIBLE (3385 785);
FORCEPROP 1 LASTPIN (3375 775) BN 5
J 0
(3363 783);
DISPLAY 0.680851 (3363 783);
PAINT GREEN (3363 783);
FORCEPROP 2 LAST CDS_LIB standard
J 0
(3425 775);
DISPLAY INVISIBLE (3425 775);
FORCEPROP 1 LAST BODY_TYPE PLUMBING
J 0
(3425 825);
DISPLAY 0.872340 (3425 825);
PAINT GREEN (3425 825);
DISPLAY INVISIBLE (3425 825);
FORCEPROP 1 LAST HDL_TAP TRUE
J 0
(3750 650);
DISPLAY 0.872340 (3750 650);
DISPLAY INVISIBLE (3750 650);
FORCEPROP 1 LAST PATH I108
J 0
(3423 775);
DISPLAY 0.872340 (3423 775);
PAINT GREEN (3423 775);
DISPLAY INVISIBLE (3423 775);
FORCEADD TAP..1
(3425 725);
FORCEPROP 3 LASTPIN (3375 725) SIG_NAME M_C_CPU0_SB_CA<4>
J 0
(3385 735);
DISPLAY 0.659574 (3385 735);
PAINT MONO (3385 735);
DISPLAY INVISIBLE (3385 735);
FORCEPROP 1 LASTPIN (3375 725) BN 4
J 0
(3363 733);
DISPLAY 0.680851 (3363 733);
PAINT GREEN (3363 733);
FORCEPROP 2 LAST CDS_LIB standard
J 0
(3425 725);
DISPLAY INVISIBLE (3425 725);
FORCEPROP 1 LAST BODY_TYPE PLUMBING
J 0
(3425 775);
DISPLAY 0.872340 (3425 775);
PAINT GREEN (3425 775);
DISPLAY INVISIBLE (3425 775);
FORCEPROP 1 LAST HDL_TAP TRUE
J 0
(3750 600);
DISPLAY 0.872340 (3750 600);
DISPLAY INVISIBLE (3750 600);
FORCEPROP 1 LAST PATH I109
J 0
(3423 725);
DISPLAY 0.872340 (3423 725);
PAINT GREEN (3423 725);
DISPLAY INVISIBLE (3423 725);
FORCEADD TAP..1
R 2
(0 -225);
FORCEPROP 3 LASTPIN (50 -225) SIG_NAME M_C_CPU0_SB_CB<2>
J 0
(60 -215);
DISPLAY 0.659574 (60 -215);
PAINT MONO (60 -215);
DISPLAY INVISIBLE (60 -215);
FORCEPROP 1 LASTPIN (50 -225) BN 2
J 2
(62 -217);
DISPLAY 0.680851 (62 -217);
PAINT GREEN (62 -217);
FORCEPROP 2 LAST CDS_LIB standard
J 0
(0 -225);
DISPLAY INVISIBLE (0 -225);
FORCEPROP 1 LAST BODY_TYPE PLUMBING
J 2
(0 -175);
DISPLAY 0.872340 (0 -175);
PAINT GREEN (0 -175);
DISPLAY INVISIBLE (0 -175);
FORCEPROP 1 LAST HDL_TAP TRUE
J 2
(-325 -350);
DISPLAY 0.872340 (-325 -350);
DISPLAY INVISIBLE (-325 -350);
FORCEPROP 1 LAST PATH I11
J 2
(2 -225);
DISPLAY 0.872340 (2 -225);
PAINT GREEN (2 -225);
DISPLAY INVISIBLE (2 -225);
FORCEADD TAP..1
(3425 675);
FORCEPROP 3 LASTPIN (3375 675) SIG_NAME M_C_CPU0_SB_CA<3>
J 0
(3385 685);
DISPLAY 0.659574 (3385 685);
PAINT MONO (3385 685);
DISPLAY INVISIBLE (3385 685);
FORCEPROP 1 LASTPIN (3375 675) BN 3
J 0
(3363 683);
DISPLAY 0.680851 (3363 683);
PAINT GREEN (3363 683);
FORCEPROP 2 LAST CDS_LIB standard
J 0
(3425 675);
DISPLAY INVISIBLE (3425 675);
FORCEPROP 1 LAST BODY_TYPE PLUMBING
J 0
(3425 725);
DISPLAY 0.872340 (3425 725);
PAINT GREEN (3425 725);
DISPLAY INVISIBLE (3425 725);
FORCEPROP 1 LAST HDL_TAP TRUE
J 0
(3750 550);
DISPLAY 0.872340 (3750 550);
DISPLAY INVISIBLE (3750 550);
FORCEPROP 1 LAST PATH I110
J 0
(3423 675);
DISPLAY 0.872340 (3423 675);
PAINT GREEN (3423 675);
DISPLAY INVISIBLE (3423 675);
FORCEADD TAP..1
(3425 1075);
FORCEPROP 3 LASTPIN (3375 1075) SIG_NAME M_C_CPU0_SA_CA<1>
J 0
(3385 1085);
DISPLAY 0.659574 (3385 1085);
PAINT MONO (3385 1085);
DISPLAY INVISIBLE (3385 1085);
FORCEPROP 1 LASTPIN (3375 1075) BN 1
J 0
(3363 1083);
DISPLAY 0.680851 (3363 1083);
PAINT GREEN (3363 1083);
FORCEPROP 2 LAST CDS_LIB standard
J 0
(3425 1075);
DISPLAY INVISIBLE (3425 1075);
FORCEPROP 1 LAST BODY_TYPE PLUMBING
J 0
(3425 1125);
DISPLAY 0.872340 (3425 1125);
PAINT GREEN (3425 1125);
DISPLAY INVISIBLE (3425 1125);
FORCEPROP 1 LAST HDL_TAP TRUE
J 0
(3750 950);
DISPLAY 0.872340 (3750 950);
DISPLAY INVISIBLE (3750 950);
FORCEPROP 1 LAST PATH I111
J 0
(3423 1075);
DISPLAY 0.872340 (3423 1075);
PAINT GREEN (3423 1075);
DISPLAY INVISIBLE (3423 1075);
FORCEADD TAP..1
(3425 1125);
FORCEPROP 3 LASTPIN (3375 1125) SIG_NAME M_C_CPU0_SA_CA<2>
J 0
(3385 1135);
DISPLAY 0.659574 (3385 1135);
PAINT MONO (3385 1135);
DISPLAY INVISIBLE (3385 1135);
FORCEPROP 1 LASTPIN (3375 1125) BN 2
J 0
(3363 1133);
DISPLAY 0.680851 (3363 1133);
PAINT GREEN (3363 1133);
FORCEPROP 2 LAST CDS_LIB standard
J 0
(3425 1125);
DISPLAY INVISIBLE (3425 1125);
FORCEPROP 1 LAST BODY_TYPE PLUMBING
J 0
(3425 1175);
DISPLAY 0.872340 (3425 1175);
PAINT GREEN (3425 1175);
DISPLAY INVISIBLE (3425 1175);
FORCEPROP 1 LAST HDL_TAP TRUE
J 0
(3750 1000);
DISPLAY 0.872340 (3750 1000);
DISPLAY INVISIBLE (3750 1000);
FORCEPROP 1 LAST PATH I112
J 0
(3423 1125);
DISPLAY 0.872340 (3423 1125);
PAINT GREEN (3423 1125);
DISPLAY INVISIBLE (3423 1125);
FORCEADD TAP..1
(3425 1175);
FORCEPROP 3 LASTPIN (3375 1175) SIG_NAME M_C_CPU0_SA_CA<3>
J 0
(3385 1185);
DISPLAY 0.659574 (3385 1185);
PAINT MONO (3385 1185);
DISPLAY INVISIBLE (3385 1185);
FORCEPROP 1 LASTPIN (3375 1175) BN 3
J 0
(3363 1183);
DISPLAY 0.680851 (3363 1183);
PAINT GREEN (3363 1183);
FORCEPROP 2 LAST CDS_LIB standard
J 0
(3425 1175);
DISPLAY INVISIBLE (3425 1175);
FORCEPROP 1 LAST BODY_TYPE PLUMBING
J 0
(3425 1225);
DISPLAY 0.872340 (3425 1225);
PAINT GREEN (3425 1225);
DISPLAY INVISIBLE (3425 1225);
FORCEPROP 1 LAST HDL_TAP TRUE
J 0
(3750 1050);
DISPLAY 0.872340 (3750 1050);
DISPLAY INVISIBLE (3750 1050);
FORCEPROP 1 LAST PATH I113
J 0
(3423 1175);
DISPLAY 0.872340 (3423 1175);
PAINT GREEN (3423 1175);
DISPLAY INVISIBLE (3423 1175);
FORCEADD TAP..1
(3425 1025);
FORCEPROP 3 LASTPIN (3375 1025) SIG_NAME M_C_CPU0_SA_CA<0>
J 0
(3385 1035);
DISPLAY 0.659574 (3385 1035);
PAINT MONO (3385 1035);
DISPLAY INVISIBLE (3385 1035);
FORCEPROP 1 LASTPIN (3375 1025) BN 0
J 0
(3363 1033);
DISPLAY 0.680851 (3363 1033);
PAINT GREEN (3363 1033);
FORCEPROP 2 LAST CDS_LIB standard
J 0
(3425 1025);
DISPLAY INVISIBLE (3425 1025);
FORCEPROP 1 LAST BODY_TYPE PLUMBING
J 0
(3425 1075);
DISPLAY 0.872340 (3425 1075);
PAINT GREEN (3425 1075);
DISPLAY INVISIBLE (3425 1075);
FORCEPROP 1 LAST HDL_TAP TRUE
J 0
(3750 900);
DISPLAY 0.872340 (3750 900);
DISPLAY INVISIBLE (3750 900);
FORCEPROP 1 LAST PATH I114
J 0
(3423 1025);
DISPLAY 0.872340 (3423 1025);
PAINT GREEN (3423 1025);
DISPLAY INVISIBLE (3423 1025);
FORCEADD TAP..1
(3425 1225);
FORCEPROP 3 LASTPIN (3375 1225) SIG_NAME M_C_CPU0_SA_CA<4>
J 0
(3385 1235);
DISPLAY 0.659574 (3385 1235);
PAINT MONO (3385 1235);
DISPLAY INVISIBLE (3385 1235);
FORCEPROP 1 LASTPIN (3375 1225) BN 4
J 0
(3363 1233);
DISPLAY 0.680851 (3363 1233);
PAINT GREEN (3363 1233);
FORCEPROP 2 LAST CDS_LIB standard
J 0
(3425 1225);
DISPLAY INVISIBLE (3425 1225);
FORCEPROP 1 LAST BODY_TYPE PLUMBING
J 0
(3425 1275);
DISPLAY 0.872340 (3425 1275);
PAINT GREEN (3425 1275);
DISPLAY INVISIBLE (3425 1275);
FORCEPROP 1 LAST HDL_TAP TRUE
J 0
(3750 1100);
DISPLAY 0.872340 (3750 1100);
DISPLAY INVISIBLE (3750 1100);
FORCEPROP 1 LAST PATH I115
J 0
(3423 1225);
DISPLAY 0.872340 (3423 1225);
PAINT GREEN (3423 1225);
DISPLAY INVISIBLE (3423 1225);
FORCEADD TAP..1
(3425 1325);
FORCEPROP 3 LASTPIN (3375 1325) SIG_NAME M_C_CPU0_SA_CA<6>
J 0
(3385 1335);
DISPLAY 0.659574 (3385 1335);
PAINT MONO (3385 1335);
DISPLAY INVISIBLE (3385 1335);
FORCEPROP 1 LASTPIN (3375 1325) BN 6
J 0
(3363 1333);
DISPLAY 0.680851 (3363 1333);
PAINT GREEN (3363 1333);
FORCEPROP 2 LAST CDS_LIB standard
J 0
(3425 1325);
DISPLAY INVISIBLE (3425 1325);
FORCEPROP 1 LAST BODY_TYPE PLUMBING
J 0
(3425 1375);
DISPLAY 0.872340 (3425 1375);
PAINT GREEN (3425 1375);
DISPLAY INVISIBLE (3425 1375);
FORCEPROP 1 LAST HDL_TAP TRUE
J 0
(3750 1200);
DISPLAY 0.872340 (3750 1200);
DISPLAY INVISIBLE (3750 1200);
FORCEPROP 1 LAST PATH I116
J 0
(3423 1325);
DISPLAY 0.872340 (3423 1325);
PAINT GREEN (3423 1325);
DISPLAY INVISIBLE (3423 1325);
FORCEADD TAP..1
(3425 1275);
FORCEPROP 3 LASTPIN (3375 1275) SIG_NAME M_C_CPU0_SA_CA<5>
J 0
(3385 1285);
DISPLAY 0.659574 (3385 1285);
PAINT MONO (3385 1285);
DISPLAY INVISIBLE (3385 1285);
FORCEPROP 1 LASTPIN (3375 1275) BN 5
J 0
(3363 1283);
DISPLAY 0.680851 (3363 1283);
PAINT GREEN (3363 1283);
FORCEPROP 2 LAST CDS_LIB standard
J 0
(3425 1275);
DISPLAY INVISIBLE (3425 1275);
FORCEPROP 1 LAST BODY_TYPE PLUMBING
J 0
(3425 1325);
DISPLAY 0.872340 (3425 1325);
PAINT GREEN (3425 1325);
DISPLAY INVISIBLE (3425 1325);
FORCEPROP 1 LAST HDL_TAP TRUE
J 0
(3750 1150);
DISPLAY 0.872340 (3750 1150);
DISPLAY INVISIBLE (3750 1150);
FORCEPROP 1 LAST PATH I117
J 0
(3423 1275);
DISPLAY 0.872340 (3423 1275);
PAINT GREEN (3423 1275);
DISPLAY INVISIBLE (3423 1275);
FORCEADD TAP..1
(3425 1525);
FORCEPROP 3 LASTPIN (3375 1525) SIG_NAME M_C_CPU0_SB_DQS_DN<1>
J 0
(3385 1535);
DISPLAY 0.659574 (3385 1535);
PAINT MONO (3385 1535);
DISPLAY INVISIBLE (3385 1535);
FORCEPROP 1 LASTPIN (3375 1525) BN 1
J 0
(3363 1533);
DISPLAY 0.680851 (3363 1533);
PAINT GREEN (3363 1533);
FORCEPROP 2 LAST CDS_LIB standard
J 0
(3425 1525);
DISPLAY INVISIBLE (3425 1525);
FORCEPROP 1 LAST BODY_TYPE PLUMBING
J 0
(3425 1575);
DISPLAY 0.872340 (3425 1575);
PAINT GREEN (3425 1575);
DISPLAY INVISIBLE (3425 1575);
FORCEPROP 1 LAST HDL_TAP TRUE
J 0
(3750 1400);
DISPLAY 0.872340 (3750 1400);
DISPLAY INVISIBLE (3750 1400);
FORCEPROP 1 LAST PATH I118
J 0
(3423 1525);
DISPLAY 0.872340 (3423 1525);
PAINT GREEN (3423 1525);
DISPLAY INVISIBLE (3423 1525);
FORCEADD TAP..1
(3425 1675);
FORCEPROP 3 LASTPIN (3375 1675) SIG_NAME M_C_CPU0_SB_DQS_DN<4>
J 0
(3385 1685);
DISPLAY 0.659574 (3385 1685);
PAINT MONO (3385 1685);
DISPLAY INVISIBLE (3385 1685);
FORCEPROP 1 LASTPIN (3375 1675) BN 4
J 0
(3363 1683);
DISPLAY 0.680851 (3363 1683);
PAINT GREEN (3363 1683);
FORCEPROP 2 LAST CDS_LIB standard
J 0
(3425 1675);
DISPLAY INVISIBLE (3425 1675);
FORCEPROP 1 LAST BODY_TYPE PLUMBING
J 0
(3425 1725);
DISPLAY 0.872340 (3425 1725);
PAINT GREEN (3425 1725);
DISPLAY INVISIBLE (3425 1725);
FORCEPROP 1 LAST HDL_TAP TRUE
J 0
(3750 1550);
DISPLAY 0.872340 (3750 1550);
DISPLAY INVISIBLE (3750 1550);
FORCEPROP 1 LAST PATH I119
J 0
(3423 1675);
DISPLAY 0.872340 (3423 1675);
PAINT GREEN (3423 1675);
DISPLAY INVISIBLE (3423 1675);
FORCEADD TAP..1
R 2
(0 -175);
FORCEPROP 3 LASTPIN (50 -175) SIG_NAME M_C_CPU0_SB_CB<3>
J 0
(60 -165);
DISPLAY 0.659574 (60 -165);
PAINT MONO (60 -165);
DISPLAY INVISIBLE (60 -165);
FORCEPROP 1 LASTPIN (50 -175) BN 3
J 2
(62 -167);
DISPLAY 0.680851 (62 -167);
PAINT GREEN (62 -167);
FORCEPROP 2 LAST CDS_LIB standard
J 0
(0 -175);
DISPLAY INVISIBLE (0 -175);
FORCEPROP 1 LAST BODY_TYPE PLUMBING
J 2
(0 -125);
DISPLAY 0.872340 (0 -125);
PAINT GREEN (0 -125);
DISPLAY INVISIBLE (0 -125);
FORCEPROP 1 LAST HDL_TAP TRUE
J 2
(-325 -300);
DISPLAY 0.872340 (-325 -300);
DISPLAY INVISIBLE (-325 -300);
FORCEPROP 1 LAST PATH I12
J 2
(2 -175);
DISPLAY 0.872340 (2 -175);
PAINT GREEN (2 -175);
DISPLAY INVISIBLE (2 -175);
FORCEADD TAP..1
(3425 1625);
FORCEPROP 3 LASTPIN (3375 1625) SIG_NAME M_C_CPU0_SB_DQS_DN<3>
J 0
(3385 1635);
DISPLAY 0.659574 (3385 1635);
PAINT MONO (3385 1635);
DISPLAY INVISIBLE (3385 1635);
FORCEPROP 1 LASTPIN (3375 1625) BN 3
J 0
(3363 1633);
DISPLAY 0.680851 (3363 1633);
PAINT GREEN (3363 1633);
FORCEPROP 2 LAST CDS_LIB standard
J 0
(3425 1625);
DISPLAY INVISIBLE (3425 1625);
FORCEPROP 1 LAST BODY_TYPE PLUMBING
J 0
(3425 1675);
DISPLAY 0.872340 (3425 1675);
PAINT GREEN (3425 1675);
DISPLAY INVISIBLE (3425 1675);
FORCEPROP 1 LAST HDL_TAP TRUE
J 0
(3750 1500);
DISPLAY 0.872340 (3750 1500);
DISPLAY INVISIBLE (3750 1500);
FORCEPROP 1 LAST PATH I120
J 0
(3423 1625);
DISPLAY 0.872340 (3423 1625);
PAINT GREEN (3423 1625);
DISPLAY INVISIBLE (3423 1625);
FORCEADD TAP..1
(3425 1575);
FORCEPROP 3 LASTPIN (3375 1575) SIG_NAME M_C_CPU0_SB_DQS_DN<2>
J 0
(3385 1585);
DISPLAY 0.659574 (3385 1585);
PAINT MONO (3385 1585);
DISPLAY INVISIBLE (3385 1585);
FORCEPROP 1 LASTPIN (3375 1575) BN 2
J 0
(3363 1583);
DISPLAY 0.680851 (3363 1583);
PAINT GREEN (3363 1583);
FORCEPROP 2 LAST CDS_LIB standard
J 0
(3425 1575);
DISPLAY INVISIBLE (3425 1575);
FORCEPROP 1 LAST BODY_TYPE PLUMBING
J 0
(3425 1625);
DISPLAY 0.872340 (3425 1625);
PAINT GREEN (3425 1625);
DISPLAY INVISIBLE (3425 1625);
FORCEPROP 1 LAST HDL_TAP TRUE
J 0
(3750 1450);
DISPLAY 0.872340 (3750 1450);
DISPLAY INVISIBLE (3750 1450);
FORCEPROP 1 LAST PATH I121
J 0
(3423 1575);
DISPLAY 0.872340 (3423 1575);
PAINT GREEN (3423 1575);
DISPLAY INVISIBLE (3423 1575);
FORCEADD TAP..1
(3425 1475);
FORCEPROP 3 LASTPIN (3375 1475) SIG_NAME M_C_CPU0_SB_DQS_DN<0>
J 0
(3385 1485);
DISPLAY 0.659574 (3385 1485);
PAINT MONO (3385 1485);
DISPLAY INVISIBLE (3385 1485);
FORCEPROP 1 LASTPIN (3375 1475) BN 0
J 0
(3363 1483);
DISPLAY 0.680851 (3363 1483);
PAINT GREEN (3363 1483);
FORCEPROP 2 LAST CDS_LIB standard
J 0
(3425 1475);
DISPLAY INVISIBLE (3425 1475);
FORCEPROP 1 LAST BODY_TYPE PLUMBING
J 0
(3425 1525);
DISPLAY 0.872340 (3425 1525);
PAINT GREEN (3425 1525);
DISPLAY INVISIBLE (3425 1525);
FORCEPROP 1 LAST HDL_TAP TRUE
J 0
(3750 1350);
DISPLAY 0.872340 (3750 1350);
DISPLAY INVISIBLE (3750 1350);
FORCEPROP 1 LAST PATH I122
J 0
(3423 1475);
DISPLAY 0.872340 (3423 1475);
PAINT GREEN (3423 1475);
DISPLAY INVISIBLE (3423 1475);
FORCEADD TAP..1
(3425 1925);
FORCEPROP 3 LASTPIN (3375 1925) SIG_NAME M_C_CPU0_SB_DQS_DN<9>
J 0
(3385 1935);
DISPLAY 0.659574 (3385 1935);
PAINT MONO (3385 1935);
DISPLAY INVISIBLE (3385 1935);
FORCEPROP 1 LASTPIN (3375 1925) BN 9
J 0
(3363 1933);
DISPLAY 0.680851 (3363 1933);
PAINT GREEN (3363 1933);
FORCEPROP 2 LAST CDS_LIB standard
J 0
(3425 1925);
DISPLAY INVISIBLE (3425 1925);
FORCEPROP 1 LAST BODY_TYPE PLUMBING
J 0
(3425 1975);
DISPLAY 0.872340 (3425 1975);
PAINT GREEN (3425 1975);
DISPLAY INVISIBLE (3425 1975);
FORCEPROP 1 LAST HDL_TAP TRUE
J 0
(3750 1800);
DISPLAY 0.872340 (3750 1800);
DISPLAY INVISIBLE (3750 1800);
FORCEPROP 1 LAST PATH I123
J 0
(3423 1925);
DISPLAY 0.872340 (3423 1925);
PAINT GREEN (3423 1925);
DISPLAY INVISIBLE (3423 1925);
FORCEADD TAP..1
(3425 1875);
FORCEPROP 3 LASTPIN (3375 1875) SIG_NAME M_C_CPU0_SB_DQS_DN<8>
J 0
(3385 1885);
DISPLAY 0.659574 (3385 1885);
PAINT MONO (3385 1885);
DISPLAY INVISIBLE (3385 1885);
FORCEPROP 1 LASTPIN (3375 1875) BN 8
J 0
(3363 1883);
DISPLAY 0.680851 (3363 1883);
PAINT GREEN (3363 1883);
FORCEPROP 2 LAST CDS_LIB standard
J 0
(3425 1875);
DISPLAY INVISIBLE (3425 1875);
FORCEPROP 1 LAST BODY_TYPE PLUMBING
J 0
(3425 1925);
DISPLAY 0.872340 (3425 1925);
PAINT GREEN (3425 1925);
DISPLAY INVISIBLE (3425 1925);
FORCEPROP 1 LAST HDL_TAP TRUE
J 0
(3750 1750);
DISPLAY 0.872340 (3750 1750);
DISPLAY INVISIBLE (3750 1750);
FORCEPROP 1 LAST PATH I124
J 0
(3423 1875);
DISPLAY 0.872340 (3423 1875);
PAINT GREEN (3423 1875);
DISPLAY INVISIBLE (3423 1875);
FORCEADD TAP..1
(3425 1825);
FORCEPROP 3 LASTPIN (3375 1825) SIG_NAME M_C_CPU0_SB_DQS_DN<7>
J 0
(3385 1835);
DISPLAY 0.659574 (3385 1835);
PAINT MONO (3385 1835);
DISPLAY INVISIBLE (3385 1835);
FORCEPROP 1 LASTPIN (3375 1825) BN 7
J 0
(3363 1833);
DISPLAY 0.680851 (3363 1833);
PAINT GREEN (3363 1833);
FORCEPROP 2 LAST CDS_LIB standard
J 0
(3425 1825);
DISPLAY INVISIBLE (3425 1825);
FORCEPROP 1 LAST BODY_TYPE PLUMBING
J 0
(3425 1875);
DISPLAY 0.872340 (3425 1875);
PAINT GREEN (3425 1875);
DISPLAY INVISIBLE (3425 1875);
FORCEPROP 1 LAST HDL_TAP TRUE
J 0
(3750 1700);
DISPLAY 0.872340 (3750 1700);
DISPLAY INVISIBLE (3750 1700);
FORCEPROP 1 LAST PATH I125
J 0
(3423 1825);
DISPLAY 0.872340 (3423 1825);
PAINT GREEN (3423 1825);
DISPLAY INVISIBLE (3423 1825);
FORCEADD TAP..1
(3425 1775);
FORCEPROP 3 LASTPIN (3375 1775) SIG_NAME M_C_CPU0_SB_DQS_DN<6>
J 0
(3385 1785);
DISPLAY 0.659574 (3385 1785);
PAINT MONO (3385 1785);
DISPLAY INVISIBLE (3385 1785);
FORCEPROP 1 LASTPIN (3375 1775) BN 6
J 0
(3363 1783);
DISPLAY 0.680851 (3363 1783);
PAINT GREEN (3363 1783);
FORCEPROP 2 LAST CDS_LIB standard
J 0
(3425 1775);
DISPLAY INVISIBLE (3425 1775);
FORCEPROP 1 LAST BODY_TYPE PLUMBING
J 0
(3425 1825);
DISPLAY 0.872340 (3425 1825);
PAINT GREEN (3425 1825);
DISPLAY INVISIBLE (3425 1825);
FORCEPROP 1 LAST HDL_TAP TRUE
J 0
(3750 1650);
DISPLAY 0.872340 (3750 1650);
DISPLAY INVISIBLE (3750 1650);
FORCEPROP 1 LAST PATH I126
J 0
(3423 1775);
DISPLAY 0.872340 (3423 1775);
PAINT GREEN (3423 1775);
DISPLAY INVISIBLE (3423 1775);
FORCEADD TAP..1
(3425 1725);
FORCEPROP 3 LASTPIN (3375 1725) SIG_NAME M_C_CPU0_SB_DQS_DN<5>
J 0
(3385 1735);
DISPLAY 0.659574 (3385 1735);
PAINT MONO (3385 1735);
DISPLAY INVISIBLE (3385 1735);
FORCEPROP 1 LASTPIN (3375 1725) BN 5
J 0
(3363 1733);
DISPLAY 0.680851 (3363 1733);
PAINT GREEN (3363 1733);
FORCEPROP 2 LAST CDS_LIB standard
J 0
(3425 1725);
DISPLAY INVISIBLE (3425 1725);
FORCEPROP 1 LAST BODY_TYPE PLUMBING
J 0
(3425 1775);
DISPLAY 0.872340 (3425 1775);
PAINT GREEN (3425 1775);
DISPLAY INVISIBLE (3425 1775);
FORCEPROP 1 LAST HDL_TAP TRUE
J 0
(3750 1600);
DISPLAY 0.872340 (3750 1600);
DISPLAY INVISIBLE (3750 1600);
FORCEPROP 1 LAST PATH I127
J 0
(3423 1725);
DISPLAY 0.872340 (3423 1725);
PAINT GREEN (3423 1725);
DISPLAY INVISIBLE (3423 1725);
FORCEADD TAP..1
(3425 2075);
FORCEPROP 3 LASTPIN (3375 2075) SIG_NAME M_C_CPU0_SB_DQS_DP<1>
J 0
(3385 2085);
DISPLAY 0.659574 (3385 2085);
PAINT MONO (3385 2085);
DISPLAY INVISIBLE (3385 2085);
FORCEPROP 1 LASTPIN (3375 2075) BN 1
J 0
(3363 2083);
DISPLAY 0.680851 (3363 2083);
PAINT GREEN (3363 2083);
FORCEPROP 2 LAST CDS_LIB standard
J 0
(3425 2075);
DISPLAY INVISIBLE (3425 2075);
FORCEPROP 1 LAST BODY_TYPE PLUMBING
J 0
(3425 2125);
DISPLAY 0.872340 (3425 2125);
PAINT GREEN (3425 2125);
DISPLAY INVISIBLE (3425 2125);
FORCEPROP 1 LAST HDL_TAP TRUE
J 0
(3750 1950);
DISPLAY 0.872340 (3750 1950);
DISPLAY INVISIBLE (3750 1950);
FORCEPROP 1 LAST PATH I128
J 0
(3423 2075);
DISPLAY 0.872340 (3423 2075);
PAINT GREEN (3423 2075);
DISPLAY INVISIBLE (3423 2075);
FORCEADD TAP..1
(3425 2125);
FORCEPROP 3 LASTPIN (3375 2125) SIG_NAME M_C_CPU0_SB_DQS_DP<2>
J 0
(3385 2135);
DISPLAY 0.659574 (3385 2135);
PAINT MONO (3385 2135);
DISPLAY INVISIBLE (3385 2135);
FORCEPROP 1 LASTPIN (3375 2125) BN 2
J 0
(3363 2133);
DISPLAY 0.680851 (3363 2133);
PAINT GREEN (3363 2133);
FORCEPROP 2 LAST CDS_LIB standard
J 0
(3425 2125);
DISPLAY INVISIBLE (3425 2125);
FORCEPROP 1 LAST BODY_TYPE PLUMBING
J 0
(3425 2175);
DISPLAY 0.872340 (3425 2175);
PAINT GREEN (3425 2175);
DISPLAY INVISIBLE (3425 2175);
FORCEPROP 1 LAST HDL_TAP TRUE
J 0
(3750 2000);
DISPLAY 0.872340 (3750 2000);
DISPLAY INVISIBLE (3750 2000);
FORCEPROP 1 LAST PATH I129
J 0
(3423 2125);
DISPLAY 0.872340 (3423 2125);
PAINT GREEN (3423 2125);
DISPLAY INVISIBLE (3423 2125);
FORCEADD TAP..1
R 2
(0 -125);
FORCEPROP 3 LASTPIN (50 -125) SIG_NAME M_C_CPU0_SB_CB<4>
J 0
(60 -115);
DISPLAY 0.659574 (60 -115);
PAINT MONO (60 -115);
DISPLAY INVISIBLE (60 -115);
FORCEPROP 1 LASTPIN (50 -125) BN 4
J 2
(62 -117);
DISPLAY 0.680851 (62 -117);
PAINT GREEN (62 -117);
FORCEPROP 2 LAST CDS_LIB standard
J 0
(0 -125);
DISPLAY INVISIBLE (0 -125);
FORCEPROP 1 LAST BODY_TYPE PLUMBING
J 2
(0 -75);
DISPLAY 0.872340 (0 -75);
PAINT GREEN (0 -75);
DISPLAY INVISIBLE (0 -75);
FORCEPROP 1 LAST HDL_TAP TRUE
J 2
(-325 -250);
DISPLAY 0.872340 (-325 -250);
DISPLAY INVISIBLE (-325 -250);
FORCEPROP 1 LAST PATH I13
J 2
(2 -125);
DISPLAY 0.872340 (2 -125);
PAINT GREEN (2 -125);
DISPLAY INVISIBLE (2 -125);
FORCEADD TAP..1
(3425 2175);
FORCEPROP 3 LASTPIN (3375 2175) SIG_NAME M_C_CPU0_SB_DQS_DP<3>
J 0
(3385 2185);
DISPLAY 0.659574 (3385 2185);
PAINT MONO (3385 2185);
DISPLAY INVISIBLE (3385 2185);
FORCEPROP 1 LASTPIN (3375 2175) BN 3
J 0
(3363 2183);
DISPLAY 0.680851 (3363 2183);
PAINT GREEN (3363 2183);
FORCEPROP 2 LAST CDS_LIB standard
J 0
(3425 2175);
DISPLAY INVISIBLE (3425 2175);
FORCEPROP 1 LAST BODY_TYPE PLUMBING
J 0
(3425 2225);
DISPLAY 0.872340 (3425 2225);
PAINT GREEN (3425 2225);
DISPLAY INVISIBLE (3425 2225);
FORCEPROP 1 LAST HDL_TAP TRUE
J 0
(3750 2050);
DISPLAY 0.872340 (3750 2050);
DISPLAY INVISIBLE (3750 2050);
FORCEPROP 1 LAST PATH I130
J 0
(3423 2175);
DISPLAY 0.872340 (3423 2175);
PAINT GREEN (3423 2175);
DISPLAY INVISIBLE (3423 2175);
FORCEADD TAP..1
(3425 2025);
FORCEPROP 3 LASTPIN (3375 2025) SIG_NAME M_C_CPU0_SB_DQS_DP<0>
J 0
(3385 2035);
DISPLAY 0.659574 (3385 2035);
PAINT MONO (3385 2035);
DISPLAY INVISIBLE (3385 2035);
FORCEPROP 1 LASTPIN (3375 2025) BN 0
J 0
(3363 2033);
DISPLAY 0.680851 (3363 2033);
PAINT GREEN (3363 2033);
FORCEPROP 2 LAST CDS_LIB standard
J 0
(3425 2025);
DISPLAY INVISIBLE (3425 2025);
FORCEPROP 1 LAST BODY_TYPE PLUMBING
J 0
(3425 2075);
DISPLAY 0.872340 (3425 2075);
PAINT GREEN (3425 2075);
DISPLAY INVISIBLE (3425 2075);
FORCEPROP 1 LAST HDL_TAP TRUE
J 0
(3750 1900);
DISPLAY 0.872340 (3750 1900);
DISPLAY INVISIBLE (3750 1900);
FORCEPROP 1 LAST PATH I131
J 0
(3423 2025);
DISPLAY 0.872340 (3423 2025);
PAINT GREEN (3423 2025);
DISPLAY INVISIBLE (3423 2025);
FORCEADD TAP..1
(3425 2275);
FORCEPROP 3 LASTPIN (3375 2275) SIG_NAME M_C_CPU0_SB_DQS_DP<5>
J 0
(3385 2285);
DISPLAY 0.659574 (3385 2285);
PAINT MONO (3385 2285);
DISPLAY INVISIBLE (3385 2285);
FORCEPROP 1 LASTPIN (3375 2275) BN 5
J 0
(3363 2283);
DISPLAY 0.680851 (3363 2283);
PAINT GREEN (3363 2283);
FORCEPROP 2 LAST CDS_LIB standard
J 0
(3425 2275);
DISPLAY INVISIBLE (3425 2275);
FORCEPROP 1 LAST BODY_TYPE PLUMBING
J 0
(3425 2325);
DISPLAY 0.872340 (3425 2325);
PAINT GREEN (3425 2325);
DISPLAY INVISIBLE (3425 2325);
FORCEPROP 1 LAST HDL_TAP TRUE
J 0
(3750 2150);
DISPLAY 0.872340 (3750 2150);
DISPLAY INVISIBLE (3750 2150);
FORCEPROP 1 LAST PATH I132
J 0
(3423 2275);
DISPLAY 0.872340 (3423 2275);
PAINT GREEN (3423 2275);
DISPLAY INVISIBLE (3423 2275);
FORCEADD TAP..1
(3425 2425);
FORCEPROP 3 LASTPIN (3375 2425) SIG_NAME M_C_CPU0_SB_DQS_DP<8>
J 0
(3385 2435);
DISPLAY 0.659574 (3385 2435);
PAINT MONO (3385 2435);
DISPLAY INVISIBLE (3385 2435);
FORCEPROP 1 LASTPIN (3375 2425) BN 8
J 0
(3363 2433);
DISPLAY 0.680851 (3363 2433);
PAINT GREEN (3363 2433);
FORCEPROP 2 LAST CDS_LIB standard
J 0
(3425 2425);
DISPLAY INVISIBLE (3425 2425);
FORCEPROP 1 LAST BODY_TYPE PLUMBING
J 0
(3425 2475);
DISPLAY 0.872340 (3425 2475);
PAINT GREEN (3425 2475);
DISPLAY INVISIBLE (3425 2475);
FORCEPROP 1 LAST HDL_TAP TRUE
J 0
(3750 2300);
DISPLAY 0.872340 (3750 2300);
DISPLAY INVISIBLE (3750 2300);
FORCEPROP 1 LAST PATH I133
J 0
(3423 2425);
DISPLAY 0.872340 (3423 2425);
PAINT GREEN (3423 2425);
DISPLAY INVISIBLE (3423 2425);
FORCEADD TAP..1
(3425 2375);
FORCEPROP 3 LASTPIN (3375 2375) SIG_NAME M_C_CPU0_SB_DQS_DP<7>
J 0
(3385 2385);
DISPLAY 0.659574 (3385 2385);
PAINT MONO (3385 2385);
DISPLAY INVISIBLE (3385 2385);
FORCEPROP 1 LASTPIN (3375 2375) BN 7
J 0
(3363 2383);
DISPLAY 0.680851 (3363 2383);
PAINT GREEN (3363 2383);
FORCEPROP 2 LAST CDS_LIB standard
J 0
(3425 2375);
DISPLAY INVISIBLE (3425 2375);
FORCEPROP 1 LAST BODY_TYPE PLUMBING
J 0
(3425 2425);
DISPLAY 0.872340 (3425 2425);
PAINT GREEN (3425 2425);
DISPLAY INVISIBLE (3425 2425);
FORCEPROP 1 LAST HDL_TAP TRUE
J 0
(3750 2250);
DISPLAY 0.872340 (3750 2250);
DISPLAY INVISIBLE (3750 2250);
FORCEPROP 1 LAST PATH I134
J 0
(3423 2375);
DISPLAY 0.872340 (3423 2375);
PAINT GREEN (3423 2375);
DISPLAY INVISIBLE (3423 2375);
FORCEADD TAP..1
(3425 2325);
FORCEPROP 3 LASTPIN (3375 2325) SIG_NAME M_C_CPU0_SB_DQS_DP<6>
J 0
(3385 2335);
DISPLAY 0.659574 (3385 2335);
PAINT MONO (3385 2335);
DISPLAY INVISIBLE (3385 2335);
FORCEPROP 1 LASTPIN (3375 2325) BN 6
J 0
(3363 2333);
DISPLAY 0.680851 (3363 2333);
PAINT GREEN (3363 2333);
FORCEPROP 2 LAST CDS_LIB standard
J 0
(3425 2325);
DISPLAY INVISIBLE (3425 2325);
FORCEPROP 1 LAST BODY_TYPE PLUMBING
J 0
(3425 2375);
DISPLAY 0.872340 (3425 2375);
PAINT GREEN (3425 2375);
DISPLAY INVISIBLE (3425 2375);
FORCEPROP 1 LAST HDL_TAP TRUE
J 0
(3750 2200);
DISPLAY 0.872340 (3750 2200);
DISPLAY INVISIBLE (3750 2200);
FORCEPROP 1 LAST PATH I135
J 0
(3423 2325);
DISPLAY 0.872340 (3423 2325);
PAINT GREEN (3423 2325);
DISPLAY INVISIBLE (3423 2325);
FORCEADD TAP..1
(3425 2225);
FORCEPROP 3 LASTPIN (3375 2225) SIG_NAME M_C_CPU0_SB_DQS_DP<4>
J 0
(3385 2235);
DISPLAY 0.659574 (3385 2235);
PAINT MONO (3385 2235);
DISPLAY INVISIBLE (3385 2235);
FORCEPROP 1 LASTPIN (3375 2225) BN 4
J 0
(3363 2233);
DISPLAY 0.680851 (3363 2233);
PAINT GREEN (3363 2233);
FORCEPROP 2 LAST CDS_LIB standard
J 0
(3425 2225);
DISPLAY INVISIBLE (3425 2225);
FORCEPROP 1 LAST BODY_TYPE PLUMBING
J 0
(3425 2275);
DISPLAY 0.872340 (3425 2275);
PAINT GREEN (3425 2275);
DISPLAY INVISIBLE (3425 2275);
FORCEPROP 1 LAST HDL_TAP TRUE
J 0
(3750 2100);
DISPLAY 0.872340 (3750 2100);
DISPLAY INVISIBLE (3750 2100);
FORCEPROP 1 LAST PATH I136
J 0
(3423 2225);
DISPLAY 0.872340 (3423 2225);
PAINT GREEN (3423 2225);
DISPLAY INVISIBLE (3423 2225);
FORCEADD TAP..1
(3425 2475);
FORCEPROP 3 LASTPIN (3375 2475) SIG_NAME M_C_CPU0_SB_DQS_DP<9>
J 0
(3385 2485);
DISPLAY 0.659574 (3385 2485);
PAINT MONO (3385 2485);
DISPLAY INVISIBLE (3385 2485);
FORCEPROP 1 LASTPIN (3375 2475) BN 9
J 0
(3363 2483);
DISPLAY 0.680851 (3363 2483);
PAINT GREEN (3363 2483);
FORCEPROP 2 LAST CDS_LIB standard
J 0
(3425 2475);
DISPLAY INVISIBLE (3425 2475);
FORCEPROP 1 LAST BODY_TYPE PLUMBING
J 0
(3425 2525);
DISPLAY 0.872340 (3425 2525);
PAINT GREEN (3425 2525);
DISPLAY INVISIBLE (3425 2525);
FORCEPROP 1 LAST HDL_TAP TRUE
J 0
(3750 2350);
DISPLAY 0.872340 (3750 2350);
DISPLAY INVISIBLE (3750 2350);
FORCEPROP 1 LAST PATH I137
J 0
(3423 2475);
DISPLAY 0.872340 (3423 2475);
PAINT GREEN (3423 2475);
DISPLAY INVISIBLE (3423 2475);
FORCEADD TAP..1
(3425 2625);
FORCEPROP 3 LASTPIN (3375 2625) SIG_NAME M_C_CPU0_SA_DQS_DN<0>
J 0
(3385 2635);
DISPLAY 0.659574 (3385 2635);
PAINT MONO (3385 2635);
DISPLAY INVISIBLE (3385 2635);
FORCEPROP 1 LASTPIN (3375 2625) BN 0
J 0
(3363 2633);
DISPLAY 0.680851 (3363 2633);
PAINT GREEN (3363 2633);
FORCEPROP 2 LAST CDS_LIB standard
J 0
(3425 2625);
DISPLAY INVISIBLE (3425 2625);
FORCEPROP 1 LAST BODY_TYPE PLUMBING
J 0
(3425 2675);
DISPLAY 0.872340 (3425 2675);
PAINT GREEN (3425 2675);
DISPLAY INVISIBLE (3425 2675);
FORCEPROP 1 LAST HDL_TAP TRUE
J 0
(3750 2500);
DISPLAY 0.872340 (3750 2500);
DISPLAY INVISIBLE (3750 2500);
FORCEPROP 1 LAST PATH I138
J 0
(3423 2625);
DISPLAY 0.872340 (3423 2625);
PAINT GREEN (3423 2625);
DISPLAY INVISIBLE (3423 2625);
FORCEADD TAP..1
(3425 2675);
FORCEPROP 3 LASTPIN (3375 2675) SIG_NAME M_C_CPU0_SA_DQS_DN<1>
J 0
(3385 2685);
DISPLAY 0.659574 (3385 2685);
PAINT MONO (3385 2685);
DISPLAY INVISIBLE (3385 2685);
FORCEPROP 1 LASTPIN (3375 2675) BN 1
J 0
(3363 2683);
DISPLAY 0.680851 (3363 2683);
PAINT GREEN (3363 2683);
FORCEPROP 2 LAST CDS_LIB standard
J 0
(3425 2675);
DISPLAY INVISIBLE (3425 2675);
FORCEPROP 1 LAST BODY_TYPE PLUMBING
J 0
(3425 2725);
DISPLAY 0.872340 (3425 2725);
PAINT GREEN (3425 2725);
DISPLAY INVISIBLE (3425 2725);
FORCEPROP 1 LAST HDL_TAP TRUE
J 0
(3750 2550);
DISPLAY 0.872340 (3750 2550);
DISPLAY INVISIBLE (3750 2550);
FORCEPROP 1 LAST PATH I139
J 0
(3423 2675);
DISPLAY 0.872340 (3423 2675);
PAINT GREEN (3423 2675);
DISPLAY INVISIBLE (3423 2675);
FORCEADD TAP..1
R 2
(0 -75);
FORCEPROP 3 LASTPIN (50 -75) SIG_NAME M_C_CPU0_SB_CB<5>
J 0
(60 -65);
DISPLAY 0.659574 (60 -65);
PAINT MONO (60 -65);
DISPLAY INVISIBLE (60 -65);
FORCEPROP 1 LASTPIN (50 -75) BN 5
J 2
(62 -67);
DISPLAY 0.680851 (62 -67);
PAINT GREEN (62 -67);
FORCEPROP 2 LAST CDS_LIB standard
J 0
(0 -75);
DISPLAY INVISIBLE (0 -75);
FORCEPROP 1 LAST BODY_TYPE PLUMBING
J 2
(0 -25);
DISPLAY 0.872340 (0 -25);
PAINT GREEN (0 -25);
DISPLAY INVISIBLE (0 -25);
FORCEPROP 1 LAST HDL_TAP TRUE
J 2
(-325 -200);
DISPLAY 0.872340 (-325 -200);
DISPLAY INVISIBLE (-325 -200);
FORCEPROP 1 LAST PATH I14
J 2
(2 -75);
DISPLAY 0.872340 (2 -75);
PAINT GREEN (2 -75);
DISPLAY INVISIBLE (2 -75);
FORCEADD TAP..1
(3425 2775);
FORCEPROP 3 LASTPIN (3375 2775) SIG_NAME M_C_CPU0_SA_DQS_DN<3>
J 0
(3385 2785);
DISPLAY 0.659574 (3385 2785);
PAINT MONO (3385 2785);
DISPLAY INVISIBLE (3385 2785);
FORCEPROP 1 LASTPIN (3375 2775) BN 3
J 0
(3363 2783);
DISPLAY 0.680851 (3363 2783);
PAINT GREEN (3363 2783);
FORCEPROP 2 LAST CDS_LIB standard
J 0
(3425 2775);
DISPLAY INVISIBLE (3425 2775);
FORCEPROP 1 LAST BODY_TYPE PLUMBING
J 0
(3425 2825);
DISPLAY 0.872340 (3425 2825);
PAINT GREEN (3425 2825);
DISPLAY INVISIBLE (3425 2825);
FORCEPROP 1 LAST HDL_TAP TRUE
J 0
(3750 2650);
DISPLAY 0.872340 (3750 2650);
DISPLAY INVISIBLE (3750 2650);
FORCEPROP 1 LAST PATH I140
J 0
(3423 2775);
DISPLAY 0.872340 (3423 2775);
PAINT GREEN (3423 2775);
DISPLAY INVISIBLE (3423 2775);
FORCEADD TAP..1
(3425 2925);
FORCEPROP 3 LASTPIN (3375 2925) SIG_NAME M_C_CPU0_SA_DQS_DN<6>
J 0
(3385 2935);
DISPLAY 0.659574 (3385 2935);
PAINT MONO (3385 2935);
DISPLAY INVISIBLE (3385 2935);
FORCEPROP 1 LASTPIN (3375 2925) BN 6
J 0
(3363 2933);
DISPLAY 0.680851 (3363 2933);
PAINT GREEN (3363 2933);
FORCEPROP 2 LAST CDS_LIB standard
J 0
(3425 2925);
DISPLAY INVISIBLE (3425 2925);
FORCEPROP 1 LAST BODY_TYPE PLUMBING
J 0
(3425 2975);
DISPLAY 0.872340 (3425 2975);
PAINT GREEN (3425 2975);
DISPLAY INVISIBLE (3425 2975);
FORCEPROP 1 LAST HDL_TAP TRUE
J 0
(3750 2800);
DISPLAY 0.872340 (3750 2800);
DISPLAY INVISIBLE (3750 2800);
FORCEPROP 1 LAST PATH I141
J 0
(3423 2925);
DISPLAY 0.872340 (3423 2925);
PAINT GREEN (3423 2925);
DISPLAY INVISIBLE (3423 2925);
FORCEADD TAP..1
(3425 2975);
FORCEPROP 3 LASTPIN (3375 2975) SIG_NAME M_C_CPU0_SA_DQS_DN<7>
J 0
(3385 2985);
DISPLAY 0.659574 (3385 2985);
PAINT MONO (3385 2985);
DISPLAY INVISIBLE (3385 2985);
FORCEPROP 1 LASTPIN (3375 2975) BN 7
J 0
(3363 2983);
DISPLAY 0.680851 (3363 2983);
PAINT GREEN (3363 2983);
FORCEPROP 2 LAST CDS_LIB standard
J 0
(3425 2975);
DISPLAY INVISIBLE (3425 2975);
FORCEPROP 1 LAST BODY_TYPE PLUMBING
J 0
(3425 3025);
DISPLAY 0.872340 (3425 3025);
PAINT GREEN (3425 3025);
DISPLAY INVISIBLE (3425 3025);
FORCEPROP 1 LAST HDL_TAP TRUE
J 0
(3750 2850);
DISPLAY 0.872340 (3750 2850);
DISPLAY INVISIBLE (3750 2850);
FORCEPROP 1 LAST PATH I142
J 0
(3423 2975);
DISPLAY 0.872340 (3423 2975);
PAINT GREEN (3423 2975);
DISPLAY INVISIBLE (3423 2975);
FORCEADD TAP..1
(3425 2875);
FORCEPROP 3 LASTPIN (3375 2875) SIG_NAME M_C_CPU0_SA_DQS_DN<5>
J 0
(3385 2885);
DISPLAY 0.659574 (3385 2885);
PAINT MONO (3385 2885);
DISPLAY INVISIBLE (3385 2885);
FORCEPROP 1 LASTPIN (3375 2875) BN 5
J 0
(3363 2883);
DISPLAY 0.680851 (3363 2883);
PAINT GREEN (3363 2883);
FORCEPROP 2 LAST CDS_LIB standard
J 0
(3425 2875);
DISPLAY INVISIBLE (3425 2875);
FORCEPROP 1 LAST BODY_TYPE PLUMBING
J 0
(3425 2925);
DISPLAY 0.872340 (3425 2925);
PAINT GREEN (3425 2925);
DISPLAY INVISIBLE (3425 2925);
FORCEPROP 1 LAST HDL_TAP TRUE
J 0
(3750 2750);
DISPLAY 0.872340 (3750 2750);
DISPLAY INVISIBLE (3750 2750);
FORCEPROP 1 LAST PATH I143
J 0
(3423 2875);
DISPLAY 0.872340 (3423 2875);
PAINT GREEN (3423 2875);
DISPLAY INVISIBLE (3423 2875);
FORCEADD TAP..1
(3425 2825);
FORCEPROP 3 LASTPIN (3375 2825) SIG_NAME M_C_CPU0_SA_DQS_DN<4>
J 0
(3385 2835);
DISPLAY 0.659574 (3385 2835);
PAINT MONO (3385 2835);
DISPLAY INVISIBLE (3385 2835);
FORCEPROP 1 LASTPIN (3375 2825) BN 4
J 0
(3363 2833);
DISPLAY 0.680851 (3363 2833);
PAINT GREEN (3363 2833);
FORCEPROP 2 LAST CDS_LIB standard
J 0
(3425 2825);
DISPLAY INVISIBLE (3425 2825);
FORCEPROP 1 LAST BODY_TYPE PLUMBING
J 0
(3425 2875);
DISPLAY 0.872340 (3425 2875);
PAINT GREEN (3425 2875);
DISPLAY INVISIBLE (3425 2875);
FORCEPROP 1 LAST HDL_TAP TRUE
J 0
(3750 2700);
DISPLAY 0.872340 (3750 2700);
DISPLAY INVISIBLE (3750 2700);
FORCEPROP 1 LAST PATH I144
J 0
(3423 2825);
DISPLAY 0.872340 (3423 2825);
PAINT GREEN (3423 2825);
DISPLAY INVISIBLE (3423 2825);
FORCEADD TAP..1
(3425 2725);
FORCEPROP 3 LASTPIN (3375 2725) SIG_NAME M_C_CPU0_SA_DQS_DN<2>
J 0
(3385 2735);
DISPLAY 0.659574 (3385 2735);
PAINT MONO (3385 2735);
DISPLAY INVISIBLE (3385 2735);
FORCEPROP 1 LASTPIN (3375 2725) BN 2
J 0
(3363 2733);
DISPLAY 0.680851 (3363 2733);
PAINT GREEN (3363 2733);
FORCEPROP 2 LAST CDS_LIB standard
J 0
(3425 2725);
DISPLAY INVISIBLE (3425 2725);
FORCEPROP 1 LAST BODY_TYPE PLUMBING
J 0
(3425 2775);
DISPLAY 0.872340 (3425 2775);
PAINT GREEN (3425 2775);
DISPLAY INVISIBLE (3425 2775);
FORCEPROP 1 LAST HDL_TAP TRUE
J 0
(3750 2600);
DISPLAY 0.872340 (3750 2600);
DISPLAY INVISIBLE (3750 2600);
FORCEPROP 1 LAST PATH I145
J 0
(3423 2725);
DISPLAY 0.872340 (3423 2725);
PAINT GREEN (3423 2725);
DISPLAY INVISIBLE (3423 2725);
FORCEADD TAP..1
(3425 3025);
FORCEPROP 3 LASTPIN (3375 3025) SIG_NAME M_C_CPU0_SA_DQS_DN<8>
J 0
(3385 3035);
DISPLAY 0.659574 (3385 3035);
PAINT MONO (3385 3035);
DISPLAY INVISIBLE (3385 3035);
FORCEPROP 1 LASTPIN (3375 3025) BN 8
J 0
(3363 3033);
DISPLAY 0.680851 (3363 3033);
PAINT GREEN (3363 3033);
FORCEPROP 2 LAST CDS_LIB standard
J 0
(3425 3025);
DISPLAY INVISIBLE (3425 3025);
FORCEPROP 1 LAST BODY_TYPE PLUMBING
J 0
(3425 3075);
DISPLAY 0.872340 (3425 3075);
PAINT GREEN (3425 3075);
DISPLAY INVISIBLE (3425 3075);
FORCEPROP 1 LAST HDL_TAP TRUE
J 0
(3750 2900);
DISPLAY 0.872340 (3750 2900);
DISPLAY INVISIBLE (3750 2900);
FORCEPROP 1 LAST PATH I146
J 0
(3423 3025);
DISPLAY 0.872340 (3423 3025);
PAINT GREEN (3423 3025);
DISPLAY INVISIBLE (3423 3025);
FORCEADD TAP..1
(3425 3225);
FORCEPROP 3 LASTPIN (3375 3225) SIG_NAME M_C_CPU0_SA_DQS_DP<1>
J 0
(3385 3235);
DISPLAY 0.659574 (3385 3235);
PAINT MONO (3385 3235);
DISPLAY INVISIBLE (3385 3235);
FORCEPROP 1 LASTPIN (3375 3225) BN 1
J 0
(3363 3233);
DISPLAY 0.680851 (3363 3233);
PAINT GREEN (3363 3233);
FORCEPROP 2 LAST CDS_LIB standard
J 0
(3425 3225);
DISPLAY INVISIBLE (3425 3225);
FORCEPROP 1 LAST BODY_TYPE PLUMBING
J 0
(3425 3275);
DISPLAY 0.872340 (3425 3275);
PAINT GREEN (3425 3275);
DISPLAY INVISIBLE (3425 3275);
FORCEPROP 1 LAST HDL_TAP TRUE
J 0
(3750 3100);
DISPLAY 0.872340 (3750 3100);
DISPLAY INVISIBLE (3750 3100);
FORCEPROP 1 LAST PATH I147
J 0
(3423 3225);
DISPLAY 0.872340 (3423 3225);
PAINT GREEN (3423 3225);
DISPLAY INVISIBLE (3423 3225);
FORCEADD TAP..1
(3425 3175);
FORCEPROP 3 LASTPIN (3375 3175) SIG_NAME M_C_CPU0_SA_DQS_DP<0>
J 0
(3385 3185);
DISPLAY 0.659574 (3385 3185);
PAINT MONO (3385 3185);
DISPLAY INVISIBLE (3385 3185);
FORCEPROP 1 LASTPIN (3375 3175) BN 0
J 0
(3363 3183);
DISPLAY 0.680851 (3363 3183);
PAINT GREEN (3363 3183);
FORCEPROP 2 LAST CDS_LIB standard
J 0
(3425 3175);
DISPLAY INVISIBLE (3425 3175);
FORCEPROP 1 LAST BODY_TYPE PLUMBING
J 0
(3425 3225);
DISPLAY 0.872340 (3425 3225);
PAINT GREEN (3425 3225);
DISPLAY INVISIBLE (3425 3225);
FORCEPROP 1 LAST HDL_TAP TRUE
J 0
(3750 3050);
DISPLAY 0.872340 (3750 3050);
DISPLAY INVISIBLE (3750 3050);
FORCEPROP 1 LAST PATH I148
J 0
(3423 3175);
DISPLAY 0.872340 (3423 3175);
PAINT GREEN (3423 3175);
DISPLAY INVISIBLE (3423 3175);
FORCEADD TAP..1
(3425 3075);
FORCEPROP 3 LASTPIN (3375 3075) SIG_NAME M_C_CPU0_SA_DQS_DN<9>
J 0
(3385 3085);
DISPLAY 0.659574 (3385 3085);
PAINT MONO (3385 3085);
DISPLAY INVISIBLE (3385 3085);
FORCEPROP 1 LASTPIN (3375 3075) BN 9
J 0
(3363 3083);
DISPLAY 0.680851 (3363 3083);
PAINT GREEN (3363 3083);
FORCEPROP 2 LAST CDS_LIB standard
J 0
(3425 3075);
DISPLAY INVISIBLE (3425 3075);
FORCEPROP 1 LAST BODY_TYPE PLUMBING
J 0
(3425 3125);
DISPLAY 0.872340 (3425 3125);
PAINT GREEN (3425 3125);
DISPLAY INVISIBLE (3425 3125);
FORCEPROP 1 LAST HDL_TAP TRUE
J 0
(3750 2950);
DISPLAY 0.872340 (3750 2950);
DISPLAY INVISIBLE (3750 2950);
FORCEPROP 1 LAST PATH I149
J 0
(3423 3075);
DISPLAY 0.872340 (3423 3075);
PAINT GREEN (3423 3075);
DISPLAY INVISIBLE (3423 3075);
FORCEADD TAP..1
R 2
(0 -25);
FORCEPROP 3 LASTPIN (50 -25) SIG_NAME M_C_CPU0_SB_CB<6>
J 0
(60 -15);
DISPLAY 0.659574 (60 -15);
PAINT MONO (60 -15);
DISPLAY INVISIBLE (60 -15);
FORCEPROP 1 LASTPIN (50 -25) BN 6
J 2
(62 -17);
DISPLAY 0.680851 (62 -17);
PAINT GREEN (62 -17);
FORCEPROP 2 LAST CDS_LIB standard
J 0
(0 -25);
DISPLAY INVISIBLE (0 -25);
FORCEPROP 1 LAST BODY_TYPE PLUMBING
J 2
(0 25);
DISPLAY 0.872340 (0 25);
PAINT GREEN (0 25);
DISPLAY INVISIBLE (0 25);
FORCEPROP 1 LAST HDL_TAP TRUE
J 2
(-325 -150);
DISPLAY 0.872340 (-325 -150);
DISPLAY INVISIBLE (-325 -150);
FORCEPROP 1 LAST PATH I15
J 2
(2 -25);
DISPLAY 0.872340 (2 -25);
PAINT GREEN (2 -25);
DISPLAY INVISIBLE (2 -25);
FORCEADD TAP..1
(3425 3325);
FORCEPROP 3 LASTPIN (3375 3325) SIG_NAME M_C_CPU0_SA_DQS_DP<3>
J 0
(3385 3335);
DISPLAY 0.659574 (3385 3335);
PAINT MONO (3385 3335);
DISPLAY INVISIBLE (3385 3335);
FORCEPROP 1 LASTPIN (3375 3325) BN 3
J 0
(3363 3333);
DISPLAY 0.680851 (3363 3333);
PAINT GREEN (3363 3333);
FORCEPROP 2 LAST CDS_LIB standard
J 0
(3425 3325);
DISPLAY INVISIBLE (3425 3325);
FORCEPROP 1 LAST BODY_TYPE PLUMBING
J 0
(3425 3375);
DISPLAY 0.872340 (3425 3375);
PAINT GREEN (3425 3375);
DISPLAY INVISIBLE (3425 3375);
FORCEPROP 1 LAST HDL_TAP TRUE
J 0
(3750 3200);
DISPLAY 0.872340 (3750 3200);
DISPLAY INVISIBLE (3750 3200);
FORCEPROP 1 LAST PATH I150
J 0
(3423 3325);
DISPLAY 0.872340 (3423 3325);
PAINT GREEN (3423 3325);
DISPLAY INVISIBLE (3423 3325);
FORCEADD TAP..1
(3425 3475);
FORCEPROP 3 LASTPIN (3375 3475) SIG_NAME M_C_CPU0_SA_DQS_DP<6>
J 0
(3385 3485);
DISPLAY 0.659574 (3385 3485);
PAINT MONO (3385 3485);
DISPLAY INVISIBLE (3385 3485);
FORCEPROP 1 LASTPIN (3375 3475) BN 6
J 0
(3363 3483);
DISPLAY 0.680851 (3363 3483);
PAINT GREEN (3363 3483);
FORCEPROP 2 LAST CDS_LIB standard
J 0
(3425 3475);
DISPLAY INVISIBLE (3425 3475);
FORCEPROP 1 LAST BODY_TYPE PLUMBING
J 0
(3425 3525);
DISPLAY 0.872340 (3425 3525);
PAINT GREEN (3425 3525);
DISPLAY INVISIBLE (3425 3525);
FORCEPROP 1 LAST HDL_TAP TRUE
J 0
(3750 3350);
DISPLAY 0.872340 (3750 3350);
DISPLAY INVISIBLE (3750 3350);
FORCEPROP 1 LAST PATH I151
J 0
(3423 3475);
DISPLAY 0.872340 (3423 3475);
PAINT GREEN (3423 3475);
DISPLAY INVISIBLE (3423 3475);
FORCEADD TAP..1
(3425 3425);
FORCEPROP 3 LASTPIN (3375 3425) SIG_NAME M_C_CPU0_SA_DQS_DP<5>
J 0
(3385 3435);
DISPLAY 0.659574 (3385 3435);
PAINT MONO (3385 3435);
DISPLAY INVISIBLE (3385 3435);
FORCEPROP 1 LASTPIN (3375 3425) BN 5
J 0
(3363 3433);
DISPLAY 0.680851 (3363 3433);
PAINT GREEN (3363 3433);
FORCEPROP 2 LAST CDS_LIB standard
J 0
(3425 3425);
DISPLAY INVISIBLE (3425 3425);
FORCEPROP 1 LAST BODY_TYPE PLUMBING
J 0
(3425 3475);
DISPLAY 0.872340 (3425 3475);
PAINT GREEN (3425 3475);
DISPLAY INVISIBLE (3425 3475);
FORCEPROP 1 LAST HDL_TAP TRUE
J 0
(3750 3300);
DISPLAY 0.872340 (3750 3300);
DISPLAY INVISIBLE (3750 3300);
FORCEPROP 1 LAST PATH I152
J 0
(3423 3425);
DISPLAY 0.872340 (3423 3425);
PAINT GREEN (3423 3425);
DISPLAY INVISIBLE (3423 3425);
FORCEADD TAP..1
(3425 3275);
FORCEPROP 3 LASTPIN (3375 3275) SIG_NAME M_C_CPU0_SA_DQS_DP<2>
J 0
(3385 3285);
DISPLAY 0.659574 (3385 3285);
PAINT MONO (3385 3285);
DISPLAY INVISIBLE (3385 3285);
FORCEPROP 1 LASTPIN (3375 3275) BN 2
J 0
(3363 3283);
DISPLAY 0.680851 (3363 3283);
PAINT GREEN (3363 3283);
FORCEPROP 2 LAST CDS_LIB standard
J 0
(3425 3275);
DISPLAY INVISIBLE (3425 3275);
FORCEPROP 1 LAST BODY_TYPE PLUMBING
J 0
(3425 3325);
DISPLAY 0.872340 (3425 3325);
PAINT GREEN (3425 3325);
DISPLAY INVISIBLE (3425 3325);
FORCEPROP 1 LAST HDL_TAP TRUE
J 0
(3750 3150);
DISPLAY 0.872340 (3750 3150);
DISPLAY INVISIBLE (3750 3150);
FORCEPROP 1 LAST PATH I153
J 0
(3423 3275);
DISPLAY 0.872340 (3423 3275);
PAINT GREEN (3423 3275);
DISPLAY INVISIBLE (3423 3275);
FORCEADD TAP..1
(3425 3375);
FORCEPROP 3 LASTPIN (3375 3375) SIG_NAME M_C_CPU0_SA_DQS_DP<4>
J 0
(3385 3385);
DISPLAY 0.659574 (3385 3385);
PAINT MONO (3385 3385);
DISPLAY INVISIBLE (3385 3385);
FORCEPROP 1 LASTPIN (3375 3375) BN 4
J 0
(3363 3383);
DISPLAY 0.680851 (3363 3383);
PAINT GREEN (3363 3383);
FORCEPROP 2 LAST CDS_LIB standard
J 0
(3425 3375);
DISPLAY INVISIBLE (3425 3375);
FORCEPROP 1 LAST BODY_TYPE PLUMBING
J 0
(3425 3425);
DISPLAY 0.872340 (3425 3425);
PAINT GREEN (3425 3425);
DISPLAY INVISIBLE (3425 3425);
FORCEPROP 1 LAST HDL_TAP TRUE
J 0
(3750 3250);
DISPLAY 0.872340 (3750 3250);
DISPLAY INVISIBLE (3750 3250);
FORCEPROP 1 LAST PATH I154
J 0
(3423 3375);
DISPLAY 0.872340 (3423 3375);
PAINT GREEN (3423 3375);
DISPLAY INVISIBLE (3423 3375);
FORCEADD TAP..1
(3425 3525);
FORCEPROP 3 LASTPIN (3375 3525) SIG_NAME M_C_CPU0_SA_DQS_DP<7>
J 0
(3385 3535);
DISPLAY 0.659574 (3385 3535);
PAINT MONO (3385 3535);
DISPLAY INVISIBLE (3385 3535);
FORCEPROP 1 LASTPIN (3375 3525) BN 7
J 0
(3363 3533);
DISPLAY 0.680851 (3363 3533);
PAINT GREEN (3363 3533);
FORCEPROP 2 LAST CDS_LIB standard
J 0
(3425 3525);
DISPLAY INVISIBLE (3425 3525);
FORCEPROP 1 LAST BODY_TYPE PLUMBING
J 0
(3425 3575);
DISPLAY 0.872340 (3425 3575);
PAINT GREEN (3425 3575);
DISPLAY INVISIBLE (3425 3575);
FORCEPROP 1 LAST HDL_TAP TRUE
J 0
(3750 3400);
DISPLAY 0.872340 (3750 3400);
DISPLAY INVISIBLE (3750 3400);
FORCEPROP 1 LAST PATH I155
J 0
(3423 3525);
DISPLAY 0.872340 (3423 3525);
PAINT GREEN (3423 3525);
DISPLAY INVISIBLE (3423 3525);
FORCEADD TAP..1
(3425 3575);
FORCEPROP 3 LASTPIN (3375 3575) SIG_NAME M_C_CPU0_SA_DQS_DP<8>
J 0
(3385 3585);
DISPLAY 0.659574 (3385 3585);
PAINT MONO (3385 3585);
DISPLAY INVISIBLE (3385 3585);
FORCEPROP 1 LASTPIN (3375 3575) BN 8
J 0
(3363 3583);
DISPLAY 0.680851 (3363 3583);
PAINT GREEN (3363 3583);
FORCEPROP 2 LAST CDS_LIB standard
J 0
(3425 3575);
DISPLAY INVISIBLE (3425 3575);
FORCEPROP 1 LAST BODY_TYPE PLUMBING
J 0
(3425 3625);
DISPLAY 0.872340 (3425 3625);
PAINT GREEN (3425 3625);
DISPLAY INVISIBLE (3425 3625);
FORCEPROP 1 LAST HDL_TAP TRUE
J 0
(3750 3450);
DISPLAY 0.872340 (3750 3450);
DISPLAY INVISIBLE (3750 3450);
FORCEPROP 1 LAST PATH I156
J 0
(3423 3575);
DISPLAY 0.872340 (3423 3575);
PAINT GREEN (3423 3575);
DISPLAY INVISIBLE (3423 3575);
FORCEADD TAP..1
(3425 3625);
FORCEPROP 3 LASTPIN (3375 3625) SIG_NAME M_C_CPU0_SA_DQS_DP<9>
J 0
(3385 3635);
DISPLAY 0.659574 (3385 3635);
PAINT MONO (3385 3635);
DISPLAY INVISIBLE (3385 3635);
FORCEPROP 1 LASTPIN (3375 3625) BN 9
J 0
(3363 3633);
DISPLAY 0.680851 (3363 3633);
PAINT GREEN (3363 3633);
FORCEPROP 2 LAST CDS_LIB standard
J 0
(3425 3625);
DISPLAY INVISIBLE (3425 3625);
FORCEPROP 1 LAST BODY_TYPE PLUMBING
J 0
(3425 3675);
DISPLAY 0.872340 (3425 3675);
PAINT GREEN (3425 3675);
DISPLAY INVISIBLE (3425 3675);
FORCEPROP 1 LAST HDL_TAP TRUE
J 0
(3750 3500);
DISPLAY 0.872340 (3750 3500);
DISPLAY INVISIBLE (3750 3500);
FORCEPROP 1 LAST PATH I157
J 0
(3423 3625);
DISPLAY 0.872340 (3423 3625);
PAINT GREEN (3423 3625);
DISPLAY INVISIBLE (3423 3625);
FORCEADD OFFPAGE..4
(4525 -275);
FORCEPROP 2 LAST $XR0 87 
J 0
(4711 -275);
DISPLAY 0.638298 (4711 -275);
PAINT MONO (4711 -275);
FORCEPROP 2 LAST CDS_LIB standard
J 0
(4525 -275);
PAINT MONO (4525 -275);
DISPLAY INVISIBLE (4525 -275);
FORCEPROP 1 LAST OFFPAGE TRUE
J 0
(4850 -400);
DISPLAY 1.170213 (4850 -400);
PAINT GREEN (4850 -400);
DISPLAY INVISIBLE (4850 -400);
FORCEPROP 1 LAST COMMENT_BODY TRUE
J 0
(4500 -375);
DISPLAY 1.170213 (4500 -375);
PAINT GREEN (4500 -375);
DISPLAY INVISIBLE (4500 -375);
FORCEPROP 2 LAST PATH I158
J 0
(4700 -200);
DISPLAY 1.021277 (4700 -200);
DISPLAY INVISIBLE (4700 -200);
FORCEADD OFFPAGE..2
(4525 50);
FORCEPROP 2 LAST $XR1 87 
J 0
(4804 50);
DISPLAY 0.638298 (4804 50);
PAINT MONO (4804 50);
FORCEPROP 2 LAST $XR0 86 
J 0
(4714 50);
DISPLAY 0.638298 (4714 50);
PAINT MONO (4714 50);
FORCEPROP 2 LAST CDS_LIB standard
J 0
(4525 50);
PAINT MONO (4525 50);
DISPLAY INVISIBLE (4525 50);
FORCEPROP 1 LAST OFFPAGE TRUE
J 0
(4850 -75);
DISPLAY 1.170213 (4850 -75);
PAINT GREEN (4850 -75);
DISPLAY INVISIBLE (4850 -75);
FORCEPROP 1 LAST COMMENT_BODY TRUE
J 0
(4480 -45);
DISPLAY 1.170213 (4480 -45);
PAINT GREEN (4480 -45);
DISPLAY INVISIBLE (4480 -45);
FORCEPROP 2 LAST PATH I159
J 0
(4700 125);
DISPLAY 1.021277 (4700 125);
DISPLAY INVISIBLE (4700 125);
FORCEADD TAP..1
R 2
(0 25);
FORCEPROP 3 LASTPIN (50 25) SIG_NAME M_C_CPU0_SB_CB<7>
J 0
(60 35);
DISPLAY 0.659574 (60 35);
PAINT MONO (60 35);
DISPLAY INVISIBLE (60 35);
FORCEPROP 1 LASTPIN (50 25) BN 7
J 2
(62 33);
DISPLAY 0.680851 (62 33);
PAINT GREEN (62 33);
FORCEPROP 2 LAST CDS_LIB standard
J 0
(0 25);
DISPLAY INVISIBLE (0 25);
FORCEPROP 1 LAST BODY_TYPE PLUMBING
J 2
(0 75);
DISPLAY 0.872340 (0 75);
PAINT GREEN (0 75);
DISPLAY INVISIBLE (0 75);
FORCEPROP 1 LAST HDL_TAP TRUE
J 2
(-325 -100);
DISPLAY 0.872340 (-325 -100);
DISPLAY INVISIBLE (-325 -100);
FORCEPROP 1 LAST PATH I16
J 2
(2 25);
DISPLAY 0.872340 (2 25);
PAINT GREEN (2 25);
DISPLAY INVISIBLE (2 25);
FORCEADD OFFPAGE..2
(4525 350);
FORCEPROP 2 LAST $XR1 87 
J 0
(4804 350);
DISPLAY 0.638298 (4804 350);
PAINT MONO (4804 350);
FORCEPROP 2 LAST $XR0 86 
J 0
(4714 350);
DISPLAY 0.638298 (4714 350);
PAINT MONO (4714 350);
FORCEPROP 2 LAST CDS_LIB standard
J 0
(4525 350);
PAINT MONO (4525 350);
DISPLAY INVISIBLE (4525 350);
FORCEPROP 1 LAST OFFPAGE TRUE
J 0
(4850 225);
DISPLAY 1.170213 (4850 225);
PAINT GREEN (4850 225);
DISPLAY INVISIBLE (4850 225);
FORCEPROP 1 LAST COMMENT_BODY TRUE
J 0
(4480 255);
DISPLAY 1.170213 (4480 255);
PAINT GREEN (4480 255);
DISPLAY INVISIBLE (4480 255);
FORCEPROP 2 LAST PATH I160
J 0
(4700 425);
DISPLAY 1.021277 (4700 425);
DISPLAY INVISIBLE (4700 425);
FORCEADD OFFPAGE..2
(4525 475);
FORCEPROP 2 LAST $XR1 87 
J 0
(4804 475);
DISPLAY 0.638298 (4804 475);
PAINT MONO (4804 475);
FORCEPROP 2 LAST $XR0 86 
J 0
(4714 475);
DISPLAY 0.638298 (4714 475);
PAINT MONO (4714 475);
FORCEPROP 2 LAST CDS_LIB standard
J 0
(4525 475);
PAINT MONO (4525 475);
DISPLAY INVISIBLE (4525 475);
FORCEPROP 1 LAST OFFPAGE TRUE
J 0
(4850 350);
DISPLAY 1.170213 (4850 350);
PAINT GREEN (4850 350);
DISPLAY INVISIBLE (4850 350);
FORCEPROP 1 LAST COMMENT_BODY TRUE
J 0
(4480 380);
DISPLAY 1.170213 (4480 380);
PAINT GREEN (4480 380);
DISPLAY INVISIBLE (4480 380);
FORCEPROP 2 LAST PATH I161
J 0
(4700 550);
DISPLAY 1.021277 (4700 550);
DISPLAY INVISIBLE (4700 550);
FORCEADD OFFPAGE..2
(4525 975);
FORCEPROP 2 LAST $XR1 87 
J 0
(4804 975);
DISPLAY 0.638298 (4804 975);
PAINT MONO (4804 975);
FORCEPROP 2 LAST $XR0 86 
J 0
(4714 975);
DISPLAY 0.638298 (4714 975);
PAINT MONO (4714 975);
FORCEPROP 2 LAST CDS_LIB standard
J 0
(4525 975);
PAINT MONO (4525 975);
DISPLAY INVISIBLE (4525 975);
FORCEPROP 1 LAST OFFPAGE TRUE
J 0
(4850 850);
DISPLAY 1.170213 (4850 850);
PAINT GREEN (4850 850);
DISPLAY INVISIBLE (4850 850);
FORCEPROP 1 LAST COMMENT_BODY TRUE
J 0
(4480 880);
DISPLAY 1.170213 (4480 880);
PAINT GREEN (4480 880);
DISPLAY INVISIBLE (4480 880);
FORCEPROP 2 LAST PATH I162
J 0
(4700 1050);
DISPLAY 1.021277 (4700 1050);
DISPLAY INVISIBLE (4700 1050);
FORCEADD OFFPAGE..3
(4525 850);
FORCEPROP 2 LAST $XR1 87 
J 0
(4829 850);
DISPLAY 0.638298 (4829 850);
PAINT MONO (4829 850);
FORCEPROP 2 LAST $XR0 86 
J 0
(4739 850);
DISPLAY 0.638298 (4739 850);
PAINT MONO (4739 850);
FORCEPROP 2 LAST CDS_LIB standard
J 2
(4525 850);
DISPLAY INVISIBLE (4525 850);
FORCEPROP 1 LAST OFFPAGE TRUE
J 0
(4850 725);
DISPLAY 0.872340 (4850 725);
DISPLAY INVISIBLE (4850 725);
FORCEPROP 1 LAST COMMENT_BODY TRUE
J 0
(4475 750);
DISPLAY 0.872340 (4475 750);
PAINT GREEN (4475 750);
DISPLAY INVISIBLE (4475 750);
FORCEPROP 2 LAST PATH I163
J 0
(4725 925);
DISPLAY 1.021277 (4725 925);
DISPLAY INVISIBLE (4725 925);
FORCEADD OFFPAGE..3
(4525 1350);
FORCEPROP 2 LAST $XR1 87 
J 0
(4829 1350);
DISPLAY 0.638298 (4829 1350);
PAINT MONO (4829 1350);
FORCEPROP 2 LAST $XR0 86 
J 0
(4739 1350);
DISPLAY 0.638298 (4739 1350);
PAINT MONO (4739 1350);
FORCEPROP 2 LAST CDS_LIB standard
J 2
(4525 1350);
DISPLAY INVISIBLE (4525 1350);
FORCEPROP 1 LAST OFFPAGE TRUE
J 0
(4850 1225);
DISPLAY 0.872340 (4850 1225);
DISPLAY INVISIBLE (4850 1225);
FORCEPROP 1 LAST COMMENT_BODY TRUE
J 0
(4475 1250);
DISPLAY 0.872340 (4475 1250);
PAINT GREEN (4475 1250);
DISPLAY INVISIBLE (4475 1250);
FORCEPROP 2 LAST PATH I164
J 0
(4725 1425);
DISPLAY 1.021277 (4725 1425);
DISPLAY INVISIBLE (4725 1425);
FORCEADD OFFPAGE..3
(4525 1950);
FORCEPROP 2 LAST $XR1 87 
J 0
(4829 1950);
DISPLAY 0.638298 (4829 1950);
PAINT MONO (4829 1950);
FORCEPROP 2 LAST $XR0 86 
J 0
(4739 1950);
DISPLAY 0.638298 (4739 1950);
PAINT MONO (4739 1950);
FORCEPROP 2 LAST CDS_LIB standard
J 2
(4525 1950);
DISPLAY INVISIBLE (4525 1950);
FORCEPROP 1 LAST OFFPAGE TRUE
J 0
(4850 1825);
DISPLAY 0.872340 (4850 1825);
DISPLAY INVISIBLE (4850 1825);
FORCEPROP 1 LAST COMMENT_BODY TRUE
J 0
(4475 1850);
DISPLAY 0.872340 (4475 1850);
PAINT GREEN (4475 1850);
DISPLAY INVISIBLE (4475 1850);
FORCEPROP 2 LAST PATH I165
J 0
(4725 2025);
DISPLAY 1.021277 (4725 2025);
DISPLAY INVISIBLE (4725 2025);
FORCEADD OFFPAGE..3
(4525 2500);
FORCEPROP 2 LAST $XR1 87 
J 0
(4829 2500);
DISPLAY 0.638298 (4829 2500);
PAINT MONO (4829 2500);
FORCEPROP 2 LAST $XR0 86 
J 0
(4739 2500);
DISPLAY 0.638298 (4739 2500);
PAINT MONO (4739 2500);
FORCEPROP 2 LAST CDS_LIB standard
J 2
(4525 2500);
DISPLAY INVISIBLE (4525 2500);
FORCEPROP 1 LAST OFFPAGE TRUE
J 0
(4850 2375);
DISPLAY 0.872340 (4850 2375);
DISPLAY INVISIBLE (4850 2375);
FORCEPROP 1 LAST COMMENT_BODY TRUE
J 0
(4475 2400);
DISPLAY 0.872340 (4475 2400);
PAINT GREEN (4475 2400);
DISPLAY INVISIBLE (4475 2400);
FORCEPROP 2 LAST PATH I166
J 0
(4725 2575);
DISPLAY 1.021277 (4725 2575);
DISPLAY INVISIBLE (4725 2575);
FORCEADD OFFPAGE..3
(4525 3100);
FORCEPROP 2 LAST $XR1 87 
J 0
(4829 3100);
DISPLAY 0.638298 (4829 3100);
PAINT MONO (4829 3100);
FORCEPROP 2 LAST $XR0 86 
J 0
(4739 3100);
DISPLAY 0.638298 (4739 3100);
PAINT MONO (4739 3100);
FORCEPROP 2 LAST CDS_LIB standard
J 2
(4525 3100);
DISPLAY INVISIBLE (4525 3100);
FORCEPROP 1 LAST OFFPAGE TRUE
J 0
(4850 2975);
DISPLAY 0.872340 (4850 2975);
DISPLAY INVISIBLE (4850 2975);
FORCEPROP 1 LAST COMMENT_BODY TRUE
J 0
(4475 3000);
DISPLAY 0.872340 (4475 3000);
PAINT GREEN (4475 3000);
DISPLAY INVISIBLE (4475 3000);
FORCEPROP 2 LAST PATH I167
J 0
(4725 3175);
DISPLAY 1.021277 (4725 3175);
DISPLAY INVISIBLE (4725 3175);
FORCEADD OFFPAGE..3
(4525 3650);
FORCEPROP 2 LAST $XR1 87 
J 0
(4829 3650);
DISPLAY 0.638298 (4829 3650);
PAINT MONO (4829 3650);
FORCEPROP 2 LAST $XR0 86 
J 0
(4739 3650);
DISPLAY 0.638298 (4739 3650);
PAINT MONO (4739 3650);
FORCEPROP 2 LAST CDS_LIB standard
J 2
(4525 3650);
DISPLAY INVISIBLE (4525 3650);
FORCEPROP 1 LAST OFFPAGE TRUE
J 0
(4850 3525);
DISPLAY 0.872340 (4850 3525);
DISPLAY INVISIBLE (4850 3525);
FORCEPROP 1 LAST COMMENT_BODY TRUE
J 0
(4475 3550);
DISPLAY 0.872340 (4475 3550);
PAINT GREEN (4475 3550);
DISPLAY INVISIBLE (4475 3550);
FORCEPROP 2 LAST PATH I168
J 0
(4725 3725);
DISPLAY 1.021277 (4725 3725);
DISPLAY INVISIBLE (4725 3725);
FORCEADD SOCKET4677_AZIF0045P001C01CS..10
(1725 1525);
FORCEPROP 1 LAST PART_NUMBER DGA^7000023
J 0
(625 3875);
DISPLAY 0.723404 (625 3875);
PAINT GREEN (625 3875);
DISPLAY INVISIBLE (625 3875);
FORCEPROP 2 LAST PART_TYPE SMLF
J 0
(625 4050);
DISPLAY 1.021277 (625 4050);
FORCEPROP 1 LAST MATERIAL IO
J 0
(625 3800);
DISPLAY 0.723404 (625 3800);
PAINT GREEN (625 3800);
FORCEPROP 2 LAST VALUE SOCKET4677_AZIF0045-P001C01CS
J 0
(625 4000);
DISPLAY 1.021277 (625 4000);
FORCEPROP 1 LAST $LOCATION U2
J 0
(625 3950);
DISPLAY 0.723404 (625 3950);
PAINT GREEN (625 3950);
FORCEPROP 0 LASTPIN (2950 -325) $PN AC48
J 0
(2960 -315);
DISPLAY 0.680851 (2960 -315);
PAINT MONO (2960 -315);
FORCEPROP 0 LASTPIN (2950 -275) $PN AD47
J 0
(2960 -265);
DISPLAY 0.680851 (2960 -265);
PAINT MONO (2960 -265);
FORCEPROP 0 LASTPIN (2950 -575) $PN AT47
J 0
(2960 -565);
DISPLAY 0.680851 (2960 -565);
PAINT MONO (2960 -565);
FORCEPROP 0 LASTPIN (2950 -475) $PN AG48
J 0
(2960 -465);
DISPLAY 0.680851 (2960 -465);
PAINT MONO (2960 -465);
FORCEPROP 0 LASTPIN (2950 -425) $PN AF47
J 0
(2960 -415);
DISPLAY 0.680851 (2960 -415);
PAINT MONO (2960 -415);
FORCEPROP 0 LASTPIN (500 -575) $PN AB49
J 2
(490 -565);
DISPLAY 0.680851 (490 -565);
PAINT MONO (490 -565);
FORCEPROP 0 LASTPIN (500 -525) $PN AF49
J 2
(490 -515);
DISPLAY 0.680851 (490 -515);
PAINT MONO (490 -515);
FORCEPROP 0 LASTPIN (500 -475) $PN AD49
J 2
(490 -465);
DISPLAY 0.680851 (490 -465);
PAINT MONO (490 -465);
FORCEPROP 0 LASTPIN (500 -425) $PN AH49
J 2
(490 -415);
DISPLAY 0.680851 (490 -415);
PAINT MONO (490 -415);
FORCEPROP 0 LASTPIN (2950 1025) $PN R52
J 0
(2960 1035);
DISPLAY 0.680851 (2960 1035);
PAINT MONO (2960 1035);
FORCEPROP 0 LASTPIN (2950 1075) $PN AA52
J 0
(2960 1085);
DISPLAY 0.680851 (2960 1085);
PAINT MONO (2960 1085);
FORCEPROP 0 LASTPIN (2950 1125) $PN T51
J 0
(2960 1135);
DISPLAY 0.680851 (2960 1135);
PAINT MONO (2960 1135);
FORCEPROP 0 LASTPIN (2950 1175) $PN Y51
J 0
(2960 1185);
DISPLAY 0.680851 (2960 1185);
PAINT MONO (2960 1185);
FORCEPROP 0 LASTPIN (2950 1225) $PN U50
J 0
(2960 1235);
DISPLAY 0.680851 (2960 1235);
PAINT MONO (2960 1235);
FORCEPROP 0 LASTPIN (2950 1275) $PN W50
J 0
(2960 1285);
DISPLAY 0.680851 (2960 1285);
PAINT MONO (2960 1285);
FORCEPROP 0 LASTPIN (2950 1325) $PN U48
J 0
(2960 1335);
DISPLAY 0.680851 (2960 1335);
PAINT MONO (2960 1335);
FORCEPROP 0 LASTPIN (500 2075) $PN U78
J 2
(490 2085);
DISPLAY 0.680851 (490 2085);
PAINT MONO (490 2085);
FORCEPROP 0 LASTPIN (500 2125) $PN T77
J 2
(490 2135);
DISPLAY 0.680851 (490 2135);
PAINT MONO (490 2135);
FORCEPROP 0 LASTPIN (500 2175) $PN W78
J 2
(490 2185);
DISPLAY 0.680851 (490 2185);
PAINT MONO (490 2185);
FORCEPROP 0 LASTPIN (500 2225) $PN Y77
J 2
(490 2235);
DISPLAY 0.680851 (490 2235);
PAINT MONO (490 2235);
FORCEPROP 0 LASTPIN (500 2275) $PN T75
J 2
(490 2285);
DISPLAY 0.680851 (490 2285);
PAINT MONO (490 2285);
FORCEPROP 0 LASTPIN (500 2325) $PN U74
J 2
(490 2335);
DISPLAY 0.680851 (490 2335);
PAINT MONO (490 2335);
FORCEPROP 0 LASTPIN (500 2375) $PN Y75
J 2
(490 2385);
DISPLAY 0.680851 (490 2385);
PAINT MONO (490 2385);
FORCEPROP 0 LASTPIN (500 2425) $PN W74
J 2
(490 2435);
DISPLAY 0.680851 (490 2435);
PAINT MONO (490 2435);
FORCEPROP 0 LASTPIN (500 2475) $PN AD69
J 2
(490 2485);
DISPLAY 0.680851 (490 2485);
PAINT MONO (490 2485);
FORCEPROP 0 LASTPIN (500 2525) $PN AC68
J 2
(490 2535);
DISPLAY 0.680851 (490 2535);
PAINT MONO (490 2535);
FORCEPROP 0 LASTPIN (500 2575) $PN AF69
J 2
(490 2585);
DISPLAY 0.680851 (490 2585);
PAINT MONO (490 2585);
FORCEPROP 0 LASTPIN (500 2625) $PN AG68
J 2
(490 2635);
DISPLAY 0.680851 (490 2635);
PAINT MONO (490 2635);
FORCEPROP 0 LASTPIN (500 2675) $PN AC66
J 2
(490 2685);
DISPLAY 0.680851 (490 2685);
PAINT MONO (490 2685);
FORCEPROP 0 LASTPIN (500 2725) $PN AD65
J 2
(490 2735);
DISPLAY 0.680851 (490 2735);
PAINT MONO (490 2735);
FORCEPROP 0 LASTPIN (500 2775) $PN AG66
J 2
(490 2785);
DISPLAY 0.680851 (490 2785);
PAINT MONO (490 2785);
FORCEPROP 0 LASTPIN (500 2825) $PN AF65
J 2
(490 2835);
DISPLAY 0.680851 (490 2835);
PAINT MONO (490 2835);
FORCEPROP 0 LASTPIN (500 2875) $PN U66
J 2
(490 2885);
DISPLAY 0.680851 (490 2885);
PAINT MONO (490 2885);
FORCEPROP 0 LASTPIN (500 2925) $PN T65
J 2
(490 2935);
DISPLAY 0.680851 (490 2935);
PAINT MONO (490 2935);
FORCEPROP 0 LASTPIN (500 2975) $PN W66
J 2
(490 2985);
DISPLAY 0.680851 (490 2985);
PAINT MONO (490 2985);
FORCEPROP 0 LASTPIN (500 3025) $PN Y65
J 2
(490 3035);
DISPLAY 0.680851 (490 3035);
PAINT MONO (490 3035);
FORCEPROP 0 LASTPIN (500 3075) $PN T63
J 2
(490 3085);
DISPLAY 0.680851 (490 3085);
PAINT MONO (490 3085);
FORCEPROP 0 LASTPIN (500 3125) $PN U62
J 2
(490 3135);
DISPLAY 0.680851 (490 3135);
PAINT MONO (490 3135);
FORCEPROP 0 LASTPIN (500 3175) $PN Y63
J 2
(490 3185);
DISPLAY 0.680851 (490 3185);
PAINT MONO (490 3185);
FORCEPROP 0 LASTPIN (500 3225) $PN W62
J 2
(490 3235);
DISPLAY 0.680851 (490 3235);
PAINT MONO (490 3235);
FORCEPROP 0 LASTPIN (500 3275) $PN AD63
J 2
(490 3285);
DISPLAY 0.680851 (490 3285);
PAINT MONO (490 3285);
FORCEPROP 0 LASTPIN (500 3325) $PN AC62
J 2
(490 3335);
DISPLAY 0.680851 (490 3335);
PAINT MONO (490 3335);
FORCEPROP 0 LASTPIN (500 3375) $PN AF63
J 2
(490 3385);
DISPLAY 0.680851 (490 3385);
PAINT MONO (490 3385);
FORCEPROP 0 LASTPIN (500 3425) $PN AG62
J 2
(490 3435);
DISPLAY 0.680851 (490 3435);
PAINT MONO (490 3435);
FORCEPROP 0 LASTPIN (500 3475) $PN AC60
J 2
(490 3485);
DISPLAY 0.680851 (490 3485);
PAINT MONO (490 3485);
FORCEPROP 0 LASTPIN (500 3525) $PN AD59
J 2
(490 3535);
DISPLAY 0.680851 (490 3535);
PAINT MONO (490 3535);
FORCEPROP 0 LASTPIN (500 3575) $PN AG60
J 2
(490 3585);
DISPLAY 0.680851 (490 3585);
PAINT MONO (490 3585);
FORCEPROP 0 LASTPIN (500 3625) $PN AF59
J 2
(490 3635);
DISPLAY 0.680851 (490 3635);
PAINT MONO (490 3635);
FORCEPROP 0 LASTPIN (2950 2625) $PN R76
J 0
(2960 2635);
DISPLAY 0.680851 (2960 2635);
PAINT MONO (2960 2635);
FORCEPROP 0 LASTPIN (2950 2675) $PN AB67
J 0
(2960 2685);
DISPLAY 0.680851 (2960 2685);
PAINT MONO (2960 2685);
FORCEPROP 0 LASTPIN (2950 2725) $PN R64
J 0
(2960 2735);
DISPLAY 0.680851 (2960 2735);
PAINT MONO (2960 2735);
FORCEPROP 0 LASTPIN (2950 2775) $PN AB61
J 0
(2960 2785);
DISPLAY 0.680851 (2960 2785);
PAINT MONO (2960 2785);
FORCEPROP 0 LASTPIN (2950 2825) $PN AD55
J 0
(2960 2835);
DISPLAY 0.680851 (2960 2835);
PAINT MONO (2960 2835);
FORCEPROP 0 LASTPIN (2950 2875) $PN W76
J 0
(2960 2885);
DISPLAY 0.680851 (2960 2885);
PAINT MONO (2960 2885);
FORCEPROP 0 LASTPIN (2950 2925) $PN AH67
J 0
(2960 2935);
DISPLAY 0.680851 (2960 2935);
PAINT MONO (2960 2935);
FORCEPROP 0 LASTPIN (2950 2975) $PN AA64
J 0
(2960 2985);
DISPLAY 0.680851 (2960 2985);
PAINT MONO (2960 2985);
FORCEPROP 0 LASTPIN (2950 3025) $PN AF61
J 0
(2960 3035);
DISPLAY 0.680851 (2960 3035);
PAINT MONO (2960 3035);
FORCEPROP 0 LASTPIN (2950 3075) $PN AH55
J 0
(2960 3085);
DISPLAY 0.680851 (2960 3085);
PAINT MONO (2960 3085);
FORCEPROP 0 LASTPIN (2950 3175) $PN U76
J 0
(2960 3185);
DISPLAY 0.680851 (2960 3185);
PAINT MONO (2960 3185);
FORCEPROP 0 LASTPIN (2950 3225) $PN AD67
J 0
(2960 3235);
DISPLAY 0.680851 (2960 3235);
PAINT MONO (2960 3235);
FORCEPROP 0 LASTPIN (2950 3275) $PN U64
J 0
(2960 3285);
DISPLAY 0.680851 (2960 3285);
PAINT MONO (2960 3285);
FORCEPROP 0 LASTPIN (2950 3325) $PN AD61
J 0
(2960 3335);
DISPLAY 0.680851 (2960 3335);
PAINT MONO (2960 3335);
FORCEPROP 0 LASTPIN (2950 3375) $PN AB55
J 0
(2960 3385);
DISPLAY 0.680851 (2960 3385);
PAINT MONO (2960 3385);
FORCEPROP 0 LASTPIN (2950 3425) $PN AA76
J 0
(2960 3435);
DISPLAY 0.680851 (2960 3435);
PAINT MONO (2960 3435);
FORCEPROP 0 LASTPIN (2950 3475) $PN AF67
J 0
(2960 3485);
DISPLAY 0.680851 (2960 3485);
PAINT MONO (2960 3485);
FORCEPROP 0 LASTPIN (2950 3525) $PN W64
J 0
(2960 3535);
DISPLAY 0.680851 (2960 3535);
PAINT MONO (2960 3535);
FORCEPROP 0 LASTPIN (2950 3575) $PN AH61
J 0
(2960 3585);
DISPLAY 0.680851 (2960 3585);
PAINT MONO (2960 3585);
FORCEPROP 0 LASTPIN (2950 3625) $PN AF55
J 0
(2960 3635);
DISPLAY 0.680851 (2960 3635);
PAINT MONO (2960 3635);
FORCEPROP 0 LASTPIN (500 1675) $PN AD57
J 2
(490 1685);
DISPLAY 0.680851 (490 1685);
PAINT MONO (490 1685);
FORCEPROP 0 LASTPIN (500 1725) $PN AC56
J 2
(490 1735);
DISPLAY 0.680851 (490 1735);
PAINT MONO (490 1735);
FORCEPROP 0 LASTPIN (500 1775) $PN AF57
J 2
(490 1785);
DISPLAY 0.680851 (490 1785);
PAINT MONO (490 1785);
FORCEPROP 0 LASTPIN (500 1825) $PN AG56
J 2
(490 1835);
DISPLAY 0.680851 (490 1835);
PAINT MONO (490 1835);
FORCEPROP 0 LASTPIN (500 1875) $PN AC54
J 2
(490 1885);
DISPLAY 0.680851 (490 1885);
PAINT MONO (490 1885);
FORCEPROP 0 LASTPIN (500 1925) $PN AD53
J 2
(490 1935);
DISPLAY 0.680851 (490 1935);
PAINT MONO (490 1935);
FORCEPROP 0 LASTPIN (500 1975) $PN AG54
J 2
(490 1985);
DISPLAY 0.680851 (490 1985);
PAINT MONO (490 1985);
FORCEPROP 0 LASTPIN (500 2025) $PN AF53
J 2
(490 2035);
DISPLAY 0.680851 (490 2035);
PAINT MONO (490 2035);
FORCEPROP 0 LASTPIN (2950 975) $PN T47
J 0
(2960 985);
DISPLAY 0.680851 (2960 985);
PAINT MONO (2960 985);
FORCEPROP 0 LASTPIN (2950 525) $PN W48
J 0
(2960 535);
DISPLAY 0.680851 (2960 535);
PAINT MONO (2960 535);
FORCEPROP 0 LASTPIN (2950 575) $PN Y47
J 0
(2960 585);
DISPLAY 0.680851 (2960 585);
PAINT MONO (2960 585);
FORCEPROP 0 LASTPIN (2950 625) $PN U41
J 0
(2960 635);
DISPLAY 0.680851 (2960 635);
PAINT MONO (2960 635);
FORCEPROP 0 LASTPIN (2950 675) $PN W41
J 0
(2960 685);
DISPLAY 0.680851 (2960 685);
PAINT MONO (2960 685);
FORCEPROP 0 LASTPIN (2950 725) $PN T40
J 0
(2960 735);
DISPLAY 0.680851 (2960 735);
PAINT MONO (2960 735);
FORCEPROP 0 LASTPIN (2950 775) $PN Y40
J 0
(2960 785);
DISPLAY 0.680851 (2960 785);
PAINT MONO (2960 785);
FORCEPROP 0 LASTPIN (2950 825) $PN R39
J 0
(2960 835);
DISPLAY 0.680851 (2960 835);
PAINT MONO (2960 835);
FORCEPROP 0 LASTPIN (500 75) $PN AD38
J 2
(490 85);
DISPLAY 0.680851 (490 85);
PAINT MONO (490 85);
FORCEPROP 0 LASTPIN (500 125) $PN AC37
J 2
(490 135);
DISPLAY 0.680851 (490 135);
PAINT MONO (490 135);
FORCEPROP 0 LASTPIN (500 175) $PN AF38
J 2
(490 185);
DISPLAY 0.680851 (490 185);
PAINT MONO (490 185);
FORCEPROP 0 LASTPIN (500 225) $PN AG37
J 2
(490 235);
DISPLAY 0.680851 (490 235);
PAINT MONO (490 235);
FORCEPROP 0 LASTPIN (500 275) $PN AC35
J 2
(490 285);
DISPLAY 0.680851 (490 285);
PAINT MONO (490 285);
FORCEPROP 0 LASTPIN (500 325) $PN AD34
J 2
(490 335);
DISPLAY 0.680851 (490 335);
PAINT MONO (490 335);
FORCEPROP 0 LASTPIN (500 375) $PN AG35
J 2
(490 385);
DISPLAY 0.680851 (490 385);
PAINT MONO (490 385);
FORCEPROP 0 LASTPIN (500 425) $PN AF34
J 2
(490 435);
DISPLAY 0.680851 (490 435);
PAINT MONO (490 435);
FORCEPROP 0 LASTPIN (500 475) $PN AD32
J 2
(490 485);
DISPLAY 0.680851 (490 485);
PAINT MONO (490 485);
FORCEPROP 0 LASTPIN (500 525) $PN AC31
J 2
(490 535);
DISPLAY 0.680851 (490 535);
PAINT MONO (490 535);
FORCEPROP 0 LASTPIN (500 575) $PN AF32
J 2
(490 585);
DISPLAY 0.680851 (490 585);
PAINT MONO (490 585);
FORCEPROP 0 LASTPIN (500 625) $PN AG31
J 2
(490 635);
DISPLAY 0.680851 (490 635);
PAINT MONO (490 635);
FORCEPROP 0 LASTPIN (500 675) $PN AC29
J 2
(490 685);
DISPLAY 0.680851 (490 685);
PAINT MONO (490 685);
FORCEPROP 0 LASTPIN (500 725) $PN AD28
J 2
(490 735);
DISPLAY 0.680851 (490 735);
PAINT MONO (490 735);
FORCEPROP 0 LASTPIN (500 775) $PN AG29
J 2
(490 785);
DISPLAY 0.680851 (490 785);
PAINT MONO (490 785);
FORCEPROP 0 LASTPIN (500 825) $PN AF28
J 2
(490 835);
DISPLAY 0.680851 (490 835);
PAINT MONO (490 835);
FORCEPROP 0 LASTPIN (500 875) $PN U23
J 2
(490 885);
DISPLAY 0.680851 (490 885);
PAINT MONO (490 885);
FORCEPROP 0 LASTPIN (500 925) $PN T22
J 2
(490 935);
DISPLAY 0.680851 (490 935);
PAINT MONO (490 935);
FORCEPROP 0 LASTPIN (500 975) $PN W23
J 2
(490 985);
DISPLAY 0.680851 (490 985);
PAINT MONO (490 985);
FORCEPROP 0 LASTPIN (500 1025) $PN Y22
J 2
(490 1035);
DISPLAY 0.680851 (490 1035);
PAINT MONO (490 1035);
FORCEPROP 0 LASTPIN (500 1075) $PN T20
J 2
(490 1085);
DISPLAY 0.680851 (490 1085);
PAINT MONO (490 1085);
FORCEPROP 0 LASTPIN (500 1125) $PN U19
J 2
(490 1135);
DISPLAY 0.680851 (490 1135);
PAINT MONO (490 1135);
FORCEPROP 0 LASTPIN (500 1175) $PN Y20
J 2
(490 1185);
DISPLAY 0.680851 (490 1185);
PAINT MONO (490 1185);
FORCEPROP 0 LASTPIN (500 1225) $PN W19
J 2
(490 1235);
DISPLAY 0.680851 (490 1235);
PAINT MONO (490 1235);
FORCEPROP 0 LASTPIN (500 1275) $PN AD20
J 2
(490 1285);
DISPLAY 0.680851 (490 1285);
PAINT MONO (490 1285);
FORCEPROP 0 LASTPIN (500 1325) $PN AC19
J 2
(490 1335);
DISPLAY 0.680851 (490 1335);
PAINT MONO (490 1335);
FORCEPROP 0 LASTPIN (500 1375) $PN AF20
J 2
(490 1385);
DISPLAY 0.680851 (490 1385);
PAINT MONO (490 1385);
FORCEPROP 0 LASTPIN (500 1425) $PN AG19
J 2
(490 1435);
DISPLAY 0.680851 (490 1435);
PAINT MONO (490 1435);
FORCEPROP 0 LASTPIN (500 1475) $PN AA17
J 2
(490 1485);
DISPLAY 0.680851 (490 1485);
PAINT MONO (490 1485);
FORCEPROP 0 LASTPIN (500 1525) $PN AG17
J 2
(490 1535);
DISPLAY 0.680851 (490 1535);
PAINT MONO (490 1535);
FORCEPROP 0 LASTPIN (500 1575) $PN AC17
J 2
(490 1585);
DISPLAY 0.680851 (490 1585);
PAINT MONO (490 1585);
FORCEPROP 0 LASTPIN (500 1625) $PN AJ17
J 2
(490 1635);
DISPLAY 0.680851 (490 1635);
PAINT MONO (490 1635);
FORCEPROP 0 LASTPIN (2950 1475) $PN AB36
J 0
(2960 1485);
DISPLAY 0.680851 (2960 1485);
PAINT MONO (2960 1485);
FORCEPROP 0 LASTPIN (2950 1525) $PN AB30
J 0
(2960 1535);
DISPLAY 0.680851 (2960 1535);
PAINT MONO (2960 1535);
FORCEPROP 0 LASTPIN (2950 1575) $PN R21
J 0
(2960 1585);
DISPLAY 0.680851 (2960 1585);
PAINT MONO (2960 1585);
FORCEPROP 0 LASTPIN (2950 1625) $PN AB18
J 0
(2960 1635);
DISPLAY 0.680851 (2960 1635);
PAINT MONO (2960 1635);
FORCEPROP 0 LASTPIN (2950 1675) $PN W33
J 0
(2960 1685);
DISPLAY 0.680851 (2960 1685);
PAINT MONO (2960 1685);
FORCEPROP 0 LASTPIN (2950 1725) $PN AF36
J 0
(2960 1735);
DISPLAY 0.680851 (2960 1735);
PAINT MONO (2960 1735);
FORCEPROP 0 LASTPIN (2950 1775) $PN AF30
J 0
(2960 1785);
DISPLAY 0.680851 (2960 1785);
PAINT MONO (2960 1785);
FORCEPROP 0 LASTPIN (2950 1825) $PN W21
J 0
(2960 1835);
DISPLAY 0.680851 (2960 1835);
PAINT MONO (2960 1835);
FORCEPROP 0 LASTPIN (2950 1875) $PN AF18
J 0
(2960 1885);
DISPLAY 0.680851 (2960 1885);
PAINT MONO (2960 1885);
FORCEPROP 0 LASTPIN (2950 1925) $PN R33
J 0
(2960 1935);
DISPLAY 0.680851 (2960 1935);
PAINT MONO (2960 1935);
FORCEPROP 0 LASTPIN (2950 2025) $PN AD36
J 0
(2960 2035);
DISPLAY 0.680851 (2960 2035);
PAINT MONO (2960 2035);
FORCEPROP 0 LASTPIN (2950 2075) $PN AD30
J 0
(2960 2085);
DISPLAY 0.680851 (2960 2085);
PAINT MONO (2960 2085);
FORCEPROP 0 LASTPIN (2950 2125) $PN U21
J 0
(2960 2135);
DISPLAY 0.680851 (2960 2135);
PAINT MONO (2960 2135);
FORCEPROP 0 LASTPIN (2950 2175) $PN AD18
J 0
(2960 2185);
DISPLAY 0.680851 (2960 2185);
PAINT MONO (2960 2185);
FORCEPROP 0 LASTPIN (2950 2225) $PN AA33
J 0
(2960 2235);
DISPLAY 0.680851 (2960 2235);
PAINT MONO (2960 2235);
FORCEPROP 0 LASTPIN (2950 2275) $PN AH36
J 0
(2960 2285);
DISPLAY 0.680851 (2960 2285);
PAINT MONO (2960 2285);
FORCEPROP 0 LASTPIN (2950 2325) $PN AH30
J 0
(2960 2335);
DISPLAY 0.680851 (2960 2335);
PAINT MONO (2960 2335);
FORCEPROP 0 LASTPIN (2950 2375) $PN AA21
J 0
(2960 2385);
DISPLAY 0.680851 (2960 2385);
PAINT MONO (2960 2385);
FORCEPROP 0 LASTPIN (2950 2425) $PN AH18
J 0
(2960 2435);
DISPLAY 0.680851 (2960 2435);
PAINT MONO (2960 2435);
FORCEPROP 0 LASTPIN (2950 2475) $PN U33
J 0
(2960 2485);
DISPLAY 0.680851 (2960 2485);
PAINT MONO (2960 2485);
FORCEPROP 0 LASTPIN (500 -325) $PN T32
J 2
(490 -315);
DISPLAY 0.680851 (490 -315);
PAINT MONO (490 -315);
FORCEPROP 0 LASTPIN (500 -275) $PN U31
J 2
(490 -265);
DISPLAY 0.680851 (490 -265);
PAINT MONO (490 -265);
FORCEPROP 0 LASTPIN (500 -225) $PN Y32
J 2
(490 -215);
DISPLAY 0.680851 (490 -215);
PAINT MONO (490 -215);
FORCEPROP 0 LASTPIN (500 -175) $PN W31
J 2
(490 -165);
DISPLAY 0.680851 (490 -165);
PAINT MONO (490 -165);
FORCEPROP 0 LASTPIN (500 -125) $PN U35
J 2
(490 -115);
DISPLAY 0.680851 (490 -115);
PAINT MONO (490 -115);
FORCEPROP 0 LASTPIN (500 -75) $PN T34
J 2
(490 -65);
DISPLAY 0.680851 (490 -65);
PAINT MONO (490 -65);
FORCEPROP 0 LASTPIN (500 -25) $PN W35
J 2
(490 -15);
DISPLAY 0.680851 (490 -15);
PAINT MONO (490 -15);
FORCEPROP 0 LASTPIN (500 25) $PN Y34
J 2
(490 35);
DISPLAY 0.680851 (490 35);
PAINT MONO (490 35);
FORCEPROP 0 LASTPIN (2950 475) $PN AA39
J 0
(2960 485);
DISPLAY 0.680851 (2960 485);
PAINT MONO (2960 485);
FORCEPROP 0 LASTPIN (2950 175) $PN U54
J 0
(2960 185);
DISPLAY 0.680851 (2960 185);
PAINT MONO (2960 185);
FORCEPROP 0 LASTPIN (2950 225) $PN T53
J 0
(2960 235);
DISPLAY 0.680851 (2960 235);
PAINT MONO (2960 235);
FORCEPROP 0 LASTPIN (2950 275) $PN W54
J 0
(2960 285);
DISPLAY 0.680851 (2960 285);
PAINT MONO (2960 285);
FORCEPROP 0 LASTPIN (2950 325) $PN Y53
J 0
(2960 335);
DISPLAY 0.680851 (2960 335);
PAINT MONO (2960 335);
FORCEPROP 0 LASTPIN (2950 -125) $PN T38
J 0
(2960 -115);
DISPLAY 0.680851 (2960 -115);
PAINT MONO (2960 -115);
FORCEPROP 0 LASTPIN (2950 -75) $PN U37
J 0
(2960 -65);
DISPLAY 0.680851 (2960 -65);
PAINT MONO (2960 -65);
FORCEPROP 0 LASTPIN (2950 -25) $PN Y38
J 0
(2960 -15);
DISPLAY 0.680851 (2960 -15);
PAINT MONO (2960 -15);
FORCEPROP 0 LASTPIN (2950 25) $PN W37
J 0
(2960 35);
DISPLAY 0.680851 (2960 35);
PAINT MONO (2960 35);
FORCEPROP 2 LAST CDS_LIB pure_quanta
J 0
(1725 1525);
DISPLAY INVISIBLE (1725 1525);
FORCEPROP 1 LAST NEEDS_NO_SIZE TRUE
J 0
(1725 1525);
DISPLAY 0.723404 (1725 1525);
PAINT GREEN (1725 1525);
DISPLAY INVISIBLE (1725 1525);
FORCEPROP 1 LAST CDS_LMAN_SYM_OUTLINE -1100,2250,1050,-2250
J 0
(1725 1525);
DISPLAY 0.468085 (1725 1525);
PAINT GREEN (1725 1525);
DISPLAY INVISIBLE (1725 1525);
FORCEPROP 2 LAST CDS_LOCATION U2
J 0
(625 4100);
DISPLAY 1.021277 (625 4100);
DISPLAY INVISIBLE (625 4100);
FORCEPROP 0 LAST $SEC 10
J 0
(625 4100);
DISPLAY 0.680851 (625 4100);
PAINT MONO (625 4100);
DISPLAY INVISIBLE (625 4100);
FORCEPROP 2 LAST CDS_SEC 10
J 0
(625 4100);
DISPLAY 1.021277 (625 4100);
DISPLAY INVISIBLE (625 4100);
FORCEPROP 1 LAST PATH I169
J 0
(1725 1525);
DISPLAY 0.723404 (1725 1525);
PAINT GREEN (1725 1525);
DISPLAY INVISIBLE (1725 1525);
FORCEADD TAP..1
R 2
(0 75);
FORCEPROP 3 LASTPIN (50 75) SIG_NAME M_C_CPU0_SB_DQ<0>
J 0
(60 85);
DISPLAY 0.659574 (60 85);
PAINT MONO (60 85);
DISPLAY INVISIBLE (60 85);
FORCEPROP 1 LASTPIN (50 75) BN 0
J 2
(62 83);
DISPLAY 0.680851 (62 83);
PAINT GREEN (62 83);
FORCEPROP 2 LAST CDS_LIB standard
J 0
(0 75);
DISPLAY INVISIBLE (0 75);
FORCEPROP 1 LAST BODY_TYPE PLUMBING
J 2
(0 125);
DISPLAY 0.872340 (0 125);
PAINT GREEN (0 125);
DISPLAY INVISIBLE (0 125);
FORCEPROP 1 LAST HDL_TAP TRUE
J 2
(-325 -50);
DISPLAY 0.872340 (-325 -50);
DISPLAY INVISIBLE (-325 -50);
FORCEPROP 1 LAST PATH I17
J 2
(2 75);
DISPLAY 0.872340 (2 75);
PAINT GREEN (2 75);
DISPLAY INVISIBLE (2 75);
FORCEADD TAP..1
R 2
(0 125);
FORCEPROP 3 LASTPIN (50 125) SIG_NAME M_C_CPU0_SB_DQ<1>
J 0
(60 135);
DISPLAY 0.659574 (60 135);
PAINT MONO (60 135);
DISPLAY INVISIBLE (60 135);
FORCEPROP 1 LASTPIN (50 125) BN 1
J 2
(62 133);
DISPLAY 0.680851 (62 133);
PAINT GREEN (62 133);
FORCEPROP 2 LAST CDS_LIB standard
J 0
(0 125);
DISPLAY INVISIBLE (0 125);
FORCEPROP 1 LAST BODY_TYPE PLUMBING
J 2
(0 175);
DISPLAY 0.872340 (0 175);
PAINT GREEN (0 175);
DISPLAY INVISIBLE (0 175);
FORCEPROP 1 LAST HDL_TAP TRUE
J 2
(-325 0);
DISPLAY 0.872340 (-325 0);
DISPLAY INVISIBLE (-325 0);
FORCEPROP 1 LAST PATH I18
J 2
(2 125);
DISPLAY 0.872340 (2 125);
PAINT GREEN (2 125);
DISPLAY INVISIBLE (2 125);
FORCEADD TAP..1
R 2
(0 175);
FORCEPROP 3 LASTPIN (50 175) SIG_NAME M_C_CPU0_SB_DQ<2>
J 0
(60 185);
DISPLAY 0.659574 (60 185);
PAINT MONO (60 185);
DISPLAY INVISIBLE (60 185);
FORCEPROP 1 LASTPIN (50 175) BN 2
J 2
(62 183);
DISPLAY 0.680851 (62 183);
PAINT GREEN (62 183);
FORCEPROP 2 LAST CDS_LIB standard
J 0
(0 175);
DISPLAY INVISIBLE (0 175);
FORCEPROP 1 LAST BODY_TYPE PLUMBING
J 2
(0 225);
DISPLAY 0.872340 (0 225);
PAINT GREEN (0 225);
DISPLAY INVISIBLE (0 225);
FORCEPROP 1 LAST HDL_TAP TRUE
J 2
(-325 50);
DISPLAY 0.872340 (-325 50);
DISPLAY INVISIBLE (-325 50);
FORCEPROP 1 LAST PATH I19
J 2
(2 175);
DISPLAY 0.872340 (2 175);
PAINT GREEN (2 175);
DISPLAY INVISIBLE (2 175);
FORCEADD OFFPAGE..2
R 2
(-1025 -500);
FORCEPROP 2 LAST $XR1 87 
J 0
(-1369 -500);
DISPLAY 0.638298 (-1369 -500);
PAINT MONO (-1369 -500);
FORCEPROP 2 LAST $XR0 86 
J 0
(-1279 -500);
DISPLAY 0.638298 (-1279 -500);
PAINT MONO (-1279 -500);
FORCEPROP 2 LAST CDS_LIB standard
J 0
(-1025 -500);
PAINT MONO (-1025 -500);
DISPLAY INVISIBLE (-1025 -500);
FORCEPROP 1 LAST OFFPAGE TRUE
J 2
(-1350 -625);
DISPLAY 0.872340 (-1350 -625);
DISPLAY INVISIBLE (-1350 -625);
FORCEPROP 1 LAST COMMENT_BODY TRUE
J 2
(-980 -595);
DISPLAY 0.872340 (-980 -595);
PAINT GREEN (-980 -595);
DISPLAY INVISIBLE (-980 -595);
FORCEPROP 2 LAST PATH I2
J 0
(-975 -425);
DISPLAY 1.021277 (-975 -425);
DISPLAY INVISIBLE (-975 -425);
FORCEADD TAP..1
R 2
(0 225);
FORCEPROP 3 LASTPIN (50 225) SIG_NAME M_C_CPU0_SB_DQ<3>
J 0
(60 235);
DISPLAY 0.659574 (60 235);
PAINT MONO (60 235);
DISPLAY INVISIBLE (60 235);
FORCEPROP 1 LASTPIN (50 225) BN 3
J 2
(62 233);
DISPLAY 0.680851 (62 233);
PAINT GREEN (62 233);
FORCEPROP 2 LAST CDS_LIB standard
J 0
(0 225);
DISPLAY INVISIBLE (0 225);
FORCEPROP 1 LAST BODY_TYPE PLUMBING
J 2
(0 275);
DISPLAY 0.872340 (0 275);
PAINT GREEN (0 275);
DISPLAY INVISIBLE (0 275);
FORCEPROP 1 LAST HDL_TAP TRUE
J 2
(-325 100);
DISPLAY 0.872340 (-325 100);
DISPLAY INVISIBLE (-325 100);
FORCEPROP 1 LAST PATH I20
J 2
(2 225);
DISPLAY 0.872340 (2 225);
PAINT GREEN (2 225);
DISPLAY INVISIBLE (2 225);
FORCEADD TAP..1
R 2
(0 275);
FORCEPROP 3 LASTPIN (50 275) SIG_NAME M_C_CPU0_SB_DQ<4>
J 0
(60 285);
DISPLAY 0.659574 (60 285);
PAINT MONO (60 285);
DISPLAY INVISIBLE (60 285);
FORCEPROP 1 LASTPIN (50 275) BN 4
J 2
(62 283);
DISPLAY 0.680851 (62 283);
PAINT GREEN (62 283);
FORCEPROP 2 LAST CDS_LIB standard
J 0
(0 275);
DISPLAY INVISIBLE (0 275);
FORCEPROP 1 LAST BODY_TYPE PLUMBING
J 2
(0 325);
DISPLAY 0.872340 (0 325);
PAINT GREEN (0 325);
DISPLAY INVISIBLE (0 325);
FORCEPROP 1 LAST HDL_TAP TRUE
J 2
(-325 150);
DISPLAY 0.872340 (-325 150);
DISPLAY INVISIBLE (-325 150);
FORCEPROP 1 LAST PATH I21
J 2
(2 275);
DISPLAY 0.872340 (2 275);
PAINT GREEN (2 275);
DISPLAY INVISIBLE (2 275);
FORCEADD TAP..1
R 2
(0 375);
FORCEPROP 3 LASTPIN (50 375) SIG_NAME M_C_CPU0_SB_DQ<6>
J 0
(60 385);
DISPLAY 0.659574 (60 385);
PAINT MONO (60 385);
DISPLAY INVISIBLE (60 385);
FORCEPROP 1 LASTPIN (50 375) BN 6
J 2
(62 383);
DISPLAY 0.680851 (62 383);
PAINT GREEN (62 383);
FORCEPROP 2 LAST CDS_LIB standard
J 0
(0 375);
DISPLAY INVISIBLE (0 375);
FORCEPROP 1 LAST BODY_TYPE PLUMBING
J 2
(0 425);
DISPLAY 0.872340 (0 425);
PAINT GREEN (0 425);
DISPLAY INVISIBLE (0 425);
FORCEPROP 1 LAST HDL_TAP TRUE
J 2
(-325 250);
DISPLAY 0.872340 (-325 250);
DISPLAY INVISIBLE (-325 250);
FORCEPROP 1 LAST PATH I22
J 2
(2 375);
DISPLAY 0.872340 (2 375);
PAINT GREEN (2 375);
DISPLAY INVISIBLE (2 375);
FORCEADD TAP..1
R 2
(0 325);
FORCEPROP 3 LASTPIN (50 325) SIG_NAME M_C_CPU0_SB_DQ<5>
J 0
(60 335);
DISPLAY 0.659574 (60 335);
PAINT MONO (60 335);
DISPLAY INVISIBLE (60 335);
FORCEPROP 1 LASTPIN (50 325) BN 5
J 2
(62 333);
DISPLAY 0.680851 (62 333);
PAINT GREEN (62 333);
FORCEPROP 2 LAST CDS_LIB standard
J 0
(0 325);
DISPLAY INVISIBLE (0 325);
FORCEPROP 1 LAST BODY_TYPE PLUMBING
J 2
(0 375);
DISPLAY 0.872340 (0 375);
PAINT GREEN (0 375);
DISPLAY INVISIBLE (0 375);
FORCEPROP 1 LAST HDL_TAP TRUE
J 2
(-325 200);
DISPLAY 0.872340 (-325 200);
DISPLAY INVISIBLE (-325 200);
FORCEPROP 1 LAST PATH I23
J 2
(2 325);
DISPLAY 0.872340 (2 325);
PAINT GREEN (2 325);
DISPLAY INVISIBLE (2 325);
FORCEADD TAP..1
R 2
(0 425);
FORCEPROP 3 LASTPIN (50 425) SIG_NAME M_C_CPU0_SB_DQ<7>
J 0
(60 435);
DISPLAY 0.659574 (60 435);
PAINT MONO (60 435);
DISPLAY INVISIBLE (60 435);
FORCEPROP 1 LASTPIN (50 425) BN 7
J 2
(62 433);
DISPLAY 0.680851 (62 433);
PAINT GREEN (62 433);
FORCEPROP 2 LAST CDS_LIB standard
J 0
(0 425);
DISPLAY INVISIBLE (0 425);
FORCEPROP 1 LAST BODY_TYPE PLUMBING
J 2
(0 475);
DISPLAY 0.872340 (0 475);
PAINT GREEN (0 475);
DISPLAY INVISIBLE (0 475);
FORCEPROP 1 LAST HDL_TAP TRUE
J 2
(-325 300);
DISPLAY 0.872340 (-325 300);
DISPLAY INVISIBLE (-325 300);
FORCEPROP 1 LAST PATH I24
J 2
(2 425);
DISPLAY 0.872340 (2 425);
PAINT GREEN (2 425);
DISPLAY INVISIBLE (2 425);
FORCEADD TAP..1
R 2
(0 475);
FORCEPROP 3 LASTPIN (50 475) SIG_NAME M_C_CPU0_SB_DQ<8>
J 0
(60 485);
DISPLAY 0.659574 (60 485);
PAINT MONO (60 485);
DISPLAY INVISIBLE (60 485);
FORCEPROP 1 LASTPIN (50 475) BN 8
J 2
(62 483);
DISPLAY 0.680851 (62 483);
PAINT GREEN (62 483);
FORCEPROP 2 LAST CDS_LIB standard
J 0
(0 475);
DISPLAY INVISIBLE (0 475);
FORCEPROP 1 LAST BODY_TYPE PLUMBING
J 2
(0 525);
DISPLAY 0.872340 (0 525);
PAINT GREEN (0 525);
DISPLAY INVISIBLE (0 525);
FORCEPROP 1 LAST HDL_TAP TRUE
J 2
(-325 350);
DISPLAY 0.872340 (-325 350);
DISPLAY INVISIBLE (-325 350);
FORCEPROP 1 LAST PATH I25
J 2
(2 475);
DISPLAY 0.872340 (2 475);
PAINT GREEN (2 475);
DISPLAY INVISIBLE (2 475);
FORCEADD TAP..1
R 2
(0 525);
FORCEPROP 3 LASTPIN (50 525) SIG_NAME M_C_CPU0_SB_DQ<9>
J 0
(60 535);
DISPLAY 0.659574 (60 535);
PAINT MONO (60 535);
DISPLAY INVISIBLE (60 535);
FORCEPROP 1 LASTPIN (50 525) BN 9
J 2
(62 533);
DISPLAY 0.680851 (62 533);
PAINT GREEN (62 533);
FORCEPROP 2 LAST CDS_LIB standard
J 0
(0 525);
DISPLAY INVISIBLE (0 525);
FORCEPROP 1 LAST BODY_TYPE PLUMBING
J 2
(0 575);
DISPLAY 0.872340 (0 575);
PAINT GREEN (0 575);
DISPLAY INVISIBLE (0 575);
FORCEPROP 1 LAST HDL_TAP TRUE
J 2
(-325 400);
DISPLAY 0.872340 (-325 400);
DISPLAY INVISIBLE (-325 400);
FORCEPROP 1 LAST PATH I26
J 2
(2 525);
DISPLAY 0.872340 (2 525);
PAINT GREEN (2 525);
DISPLAY INVISIBLE (2 525);
FORCEADD TAP..1
R 2
(0 575);
FORCEPROP 3 LASTPIN (50 575) SIG_NAME M_C_CPU0_SB_DQ<10>
J 0
(60 585);
DISPLAY 0.659574 (60 585);
PAINT MONO (60 585);
DISPLAY INVISIBLE (60 585);
FORCEPROP 1 LASTPIN (50 575) BN 10
J 2
(62 583);
DISPLAY 0.680851 (62 583);
PAINT GREEN (62 583);
FORCEPROP 2 LAST CDS_LIB standard
J 0
(0 575);
DISPLAY INVISIBLE (0 575);
FORCEPROP 1 LAST BODY_TYPE PLUMBING
J 2
(0 625);
DISPLAY 0.872340 (0 625);
PAINT GREEN (0 625);
DISPLAY INVISIBLE (0 625);
FORCEPROP 1 LAST HDL_TAP TRUE
J 2
(-325 450);
DISPLAY 0.872340 (-325 450);
DISPLAY INVISIBLE (-325 450);
FORCEPROP 1 LAST PATH I27
J 2
(2 575);
DISPLAY 0.872340 (2 575);
PAINT GREEN (2 575);
DISPLAY INVISIBLE (2 575);
FORCEADD TAP..1
R 2
(0 625);
FORCEPROP 3 LASTPIN (50 625) SIG_NAME M_C_CPU0_SB_DQ<11>
J 0
(60 635);
DISPLAY 0.659574 (60 635);
PAINT MONO (60 635);
DISPLAY INVISIBLE (60 635);
FORCEPROP 1 LASTPIN (50 625) BN 11
J 2
(62 633);
DISPLAY 0.680851 (62 633);
PAINT GREEN (62 633);
FORCEPROP 2 LAST CDS_LIB standard
J 0
(0 625);
DISPLAY INVISIBLE (0 625);
FORCEPROP 1 LAST BODY_TYPE PLUMBING
J 2
(0 675);
DISPLAY 0.872340 (0 675);
PAINT GREEN (0 675);
DISPLAY INVISIBLE (0 675);
FORCEPROP 1 LAST HDL_TAP TRUE
J 2
(-325 500);
DISPLAY 0.872340 (-325 500);
DISPLAY INVISIBLE (-325 500);
FORCEPROP 1 LAST PATH I28
J 2
(2 625);
DISPLAY 0.872340 (2 625);
PAINT GREEN (2 625);
DISPLAY INVISIBLE (2 625);
FORCEADD TAP..1
R 2
(0 675);
FORCEPROP 3 LASTPIN (50 675) SIG_NAME M_C_CPU0_SB_DQ<12>
J 0
(60 685);
DISPLAY 0.659574 (60 685);
PAINT MONO (60 685);
DISPLAY INVISIBLE (60 685);
FORCEPROP 1 LASTPIN (50 675) BN 12
J 2
(62 683);
DISPLAY 0.680851 (62 683);
PAINT GREEN (62 683);
FORCEPROP 2 LAST CDS_LIB standard
J 0
(0 675);
DISPLAY INVISIBLE (0 675);
FORCEPROP 1 LAST BODY_TYPE PLUMBING
J 2
(0 725);
DISPLAY 0.872340 (0 725);
PAINT GREEN (0 725);
DISPLAY INVISIBLE (0 725);
FORCEPROP 1 LAST HDL_TAP TRUE
J 2
(-325 550);
DISPLAY 0.872340 (-325 550);
DISPLAY INVISIBLE (-325 550);
FORCEPROP 1 LAST PATH I29
J 2
(2 675);
DISPLAY 0.872340 (2 675);
PAINT GREEN (2 675);
DISPLAY INVISIBLE (2 675);
FORCEADD TAP..1
R 2
(0 -575);
FORCEPROP 3 LASTPIN (50 -575) SIG_NAME M_C_CPU0_CLK_DN<0>
J 0
(60 -565);
DISPLAY 0.659574 (60 -565);
PAINT MONO (60 -565);
DISPLAY INVISIBLE (60 -565);
FORCEPROP 1 LASTPIN (50 -575) BN 0
J 2
(62 -567);
DISPLAY 0.680851 (62 -567);
PAINT GREEN (62 -567);
FORCEPROP 2 LAST CDS_LIB standard
J 0
(0 -575);
DISPLAY INVISIBLE (0 -575);
FORCEPROP 1 LAST BODY_TYPE PLUMBING
J 2
(0 -525);
DISPLAY 0.872340 (0 -525);
PAINT GREEN (0 -525);
DISPLAY INVISIBLE (0 -525);
FORCEPROP 1 LAST HDL_TAP TRUE
J 2
(-325 -700);
DISPLAY 0.872340 (-325 -700);
DISPLAY INVISIBLE (-325 -700);
FORCEPROP 1 LAST PATH I3
J 2
(2 -575);
DISPLAY 0.872340 (2 -575);
PAINT GREEN (2 -575);
DISPLAY INVISIBLE (2 -575);
FORCEADD TAP..1
R 2
(0 775);
FORCEPROP 3 LASTPIN (50 775) SIG_NAME M_C_CPU0_SB_DQ<14>
J 0
(60 785);
DISPLAY 0.659574 (60 785);
PAINT MONO (60 785);
DISPLAY INVISIBLE (60 785);
FORCEPROP 1 LASTPIN (50 775) BN 14
J 2
(62 783);
DISPLAY 0.680851 (62 783);
PAINT GREEN (62 783);
FORCEPROP 2 LAST CDS_LIB standard
J 0
(0 775);
DISPLAY INVISIBLE (0 775);
FORCEPROP 1 LAST BODY_TYPE PLUMBING
J 2
(0 825);
DISPLAY 0.872340 (0 825);
PAINT GREEN (0 825);
DISPLAY INVISIBLE (0 825);
FORCEPROP 1 LAST HDL_TAP TRUE
J 2
(-325 650);
DISPLAY 0.872340 (-325 650);
DISPLAY INVISIBLE (-325 650);
FORCEPROP 1 LAST PATH I30
J 2
(2 775);
DISPLAY 0.872340 (2 775);
PAINT GREEN (2 775);
DISPLAY INVISIBLE (2 775);
FORCEADD TAP..1
R 2
(0 725);
FORCEPROP 3 LASTPIN (50 725) SIG_NAME M_C_CPU0_SB_DQ<13>
J 0
(60 735);
DISPLAY 0.659574 (60 735);
PAINT MONO (60 735);
DISPLAY INVISIBLE (60 735);
FORCEPROP 1 LASTPIN (50 725) BN 13
J 2
(62 733);
DISPLAY 0.680851 (62 733);
PAINT GREEN (62 733);
FORCEPROP 2 LAST CDS_LIB standard
J 0
(0 725);
DISPLAY INVISIBLE (0 725);
FORCEPROP 1 LAST BODY_TYPE PLUMBING
J 2
(0 775);
DISPLAY 0.872340 (0 775);
PAINT GREEN (0 775);
DISPLAY INVISIBLE (0 775);
FORCEPROP 1 LAST HDL_TAP TRUE
J 2
(-325 600);
DISPLAY 0.872340 (-325 600);
DISPLAY INVISIBLE (-325 600);
FORCEPROP 1 LAST PATH I31
J 2
(2 725);
DISPLAY 0.872340 (2 725);
PAINT GREEN (2 725);
DISPLAY INVISIBLE (2 725);
FORCEADD TAP..1
R 2
(0 825);
FORCEPROP 3 LASTPIN (50 825) SIG_NAME M_C_CPU0_SB_DQ<15>
J 0
(60 835);
DISPLAY 0.659574 (60 835);
PAINT MONO (60 835);
DISPLAY INVISIBLE (60 835);
FORCEPROP 1 LASTPIN (50 825) BN 15
J 2
(62 833);
DISPLAY 0.680851 (62 833);
PAINT GREEN (62 833);
FORCEPROP 2 LAST CDS_LIB standard
J 0
(0 825);
DISPLAY INVISIBLE (0 825);
FORCEPROP 1 LAST BODY_TYPE PLUMBING
J 2
(0 875);
DISPLAY 0.872340 (0 875);
PAINT GREEN (0 875);
DISPLAY INVISIBLE (0 875);
FORCEPROP 1 LAST HDL_TAP TRUE
J 2
(-325 700);
DISPLAY 0.872340 (-325 700);
DISPLAY INVISIBLE (-325 700);
FORCEPROP 1 LAST PATH I32
J 2
(2 825);
DISPLAY 0.872340 (2 825);
PAINT GREEN (2 825);
DISPLAY INVISIBLE (2 825);
FORCEADD TAP..1
R 2
(0 875);
FORCEPROP 3 LASTPIN (50 875) SIG_NAME M_C_CPU0_SB_DQ<16>
J 0
(60 885);
DISPLAY 0.659574 (60 885);
PAINT MONO (60 885);
DISPLAY INVISIBLE (60 885);
FORCEPROP 1 LASTPIN (50 875) BN 16
J 2
(62 883);
DISPLAY 0.680851 (62 883);
PAINT GREEN (62 883);
FORCEPROP 2 LAST CDS_LIB standard
J 0
(0 875);
DISPLAY INVISIBLE (0 875);
FORCEPROP 1 LAST BODY_TYPE PLUMBING
J 2
(0 925);
DISPLAY 0.872340 (0 925);
PAINT GREEN (0 925);
DISPLAY INVISIBLE (0 925);
FORCEPROP 1 LAST HDL_TAP TRUE
J 2
(-325 750);
DISPLAY 0.872340 (-325 750);
DISPLAY INVISIBLE (-325 750);
FORCEPROP 1 LAST PATH I33
J 2
(2 875);
DISPLAY 0.872340 (2 875);
PAINT GREEN (2 875);
DISPLAY INVISIBLE (2 875);
FORCEADD TAP..1
R 2
(0 925);
FORCEPROP 3 LASTPIN (50 925) SIG_NAME M_C_CPU0_SB_DQ<17>
J 0
(60 935);
DISPLAY 0.659574 (60 935);
PAINT MONO (60 935);
DISPLAY INVISIBLE (60 935);
FORCEPROP 1 LASTPIN (50 925) BN 17
J 2
(62 933);
DISPLAY 0.680851 (62 933);
PAINT GREEN (62 933);
FORCEPROP 2 LAST CDS_LIB standard
J 0
(0 925);
DISPLAY INVISIBLE (0 925);
FORCEPROP 1 LAST BODY_TYPE PLUMBING
J 2
(0 975);
DISPLAY 0.872340 (0 975);
PAINT GREEN (0 975);
DISPLAY INVISIBLE (0 975);
FORCEPROP 1 LAST HDL_TAP TRUE
J 2
(-325 800);
DISPLAY 0.872340 (-325 800);
DISPLAY INVISIBLE (-325 800);
FORCEPROP 1 LAST PATH I34
J 2
(2 925);
DISPLAY 0.872340 (2 925);
PAINT GREEN (2 925);
DISPLAY INVISIBLE (2 925);
FORCEADD TAP..1
R 2
(0 1025);
FORCEPROP 3 LASTPIN (50 1025) SIG_NAME M_C_CPU0_SB_DQ<19>
J 0
(60 1035);
DISPLAY 0.659574 (60 1035);
PAINT MONO (60 1035);
DISPLAY INVISIBLE (60 1035);
FORCEPROP 1 LASTPIN (50 1025) BN 19
J 2
(62 1033);
DISPLAY 0.680851 (62 1033);
PAINT GREEN (62 1033);
FORCEPROP 2 LAST CDS_LIB standard
J 0
(0 1025);
DISPLAY INVISIBLE (0 1025);
FORCEPROP 1 LAST BODY_TYPE PLUMBING
J 2
(0 1075);
DISPLAY 0.872340 (0 1075);
PAINT GREEN (0 1075);
DISPLAY INVISIBLE (0 1075);
FORCEPROP 1 LAST HDL_TAP TRUE
J 2
(-325 900);
DISPLAY 0.872340 (-325 900);
DISPLAY INVISIBLE (-325 900);
FORCEPROP 1 LAST PATH I35
J 2
(2 1025);
DISPLAY 0.872340 (2 1025);
PAINT GREEN (2 1025);
DISPLAY INVISIBLE (2 1025);
FORCEADD TAP..1
R 2
(0 975);
FORCEPROP 3 LASTPIN (50 975) SIG_NAME M_C_CPU0_SB_DQ<18>
J 0
(60 985);
DISPLAY 0.659574 (60 985);
PAINT MONO (60 985);
DISPLAY INVISIBLE (60 985);
FORCEPROP 1 LASTPIN (50 975) BN 18
J 2
(62 983);
DISPLAY 0.680851 (62 983);
PAINT GREEN (62 983);
FORCEPROP 2 LAST CDS_LIB standard
J 0
(0 975);
DISPLAY INVISIBLE (0 975);
FORCEPROP 1 LAST BODY_TYPE PLUMBING
J 2
(0 1025);
DISPLAY 0.872340 (0 1025);
PAINT GREEN (0 1025);
DISPLAY INVISIBLE (0 1025);
FORCEPROP 1 LAST HDL_TAP TRUE
J 2
(-325 850);
DISPLAY 0.872340 (-325 850);
DISPLAY INVISIBLE (-325 850);
FORCEPROP 1 LAST PATH I36
J 2
(2 975);
DISPLAY 0.872340 (2 975);
PAINT GREEN (2 975);
DISPLAY INVISIBLE (2 975);
FORCEADD TAP..1
R 2
(0 1075);
FORCEPROP 3 LASTPIN (50 1075) SIG_NAME M_C_CPU0_SB_DQ<20>
J 0
(60 1085);
DISPLAY 0.659574 (60 1085);
PAINT MONO (60 1085);
DISPLAY INVISIBLE (60 1085);
FORCEPROP 1 LASTPIN (50 1075) BN 20
J 2
(62 1083);
DISPLAY 0.680851 (62 1083);
PAINT GREEN (62 1083);
FORCEPROP 2 LAST CDS_LIB standard
J 0
(0 1075);
DISPLAY INVISIBLE (0 1075);
FORCEPROP 1 LAST BODY_TYPE PLUMBING
J 2
(0 1125);
DISPLAY 0.872340 (0 1125);
PAINT GREEN (0 1125);
DISPLAY INVISIBLE (0 1125);
FORCEPROP 1 LAST HDL_TAP TRUE
J 2
(-325 950);
DISPLAY 0.872340 (-325 950);
DISPLAY INVISIBLE (-325 950);
FORCEPROP 1 LAST PATH I37
J 2
(2 1075);
DISPLAY 0.872340 (2 1075);
PAINT GREEN (2 1075);
DISPLAY INVISIBLE (2 1075);
FORCEADD TAP..1
R 2
(0 1125);
FORCEPROP 3 LASTPIN (50 1125) SIG_NAME M_C_CPU0_SB_DQ<21>
J 0
(60 1135);
DISPLAY 0.659574 (60 1135);
PAINT MONO (60 1135);
DISPLAY INVISIBLE (60 1135);
FORCEPROP 1 LASTPIN (50 1125) BN 21
J 2
(62 1133);
DISPLAY 0.680851 (62 1133);
PAINT GREEN (62 1133);
FORCEPROP 2 LAST CDS_LIB standard
J 0
(0 1125);
DISPLAY INVISIBLE (0 1125);
FORCEPROP 1 LAST BODY_TYPE PLUMBING
J 2
(0 1175);
DISPLAY 0.872340 (0 1175);
PAINT GREEN (0 1175);
DISPLAY INVISIBLE (0 1175);
FORCEPROP 1 LAST HDL_TAP TRUE
J 2
(-325 1000);
DISPLAY 0.872340 (-325 1000);
DISPLAY INVISIBLE (-325 1000);
FORCEPROP 1 LAST PATH I38
J 2
(2 1125);
DISPLAY 0.872340 (2 1125);
PAINT GREEN (2 1125);
DISPLAY INVISIBLE (2 1125);
FORCEADD TAP..1
R 2
(0 1175);
FORCEPROP 3 LASTPIN (50 1175) SIG_NAME M_C_CPU0_SB_DQ<22>
J 0
(60 1185);
DISPLAY 0.659574 (60 1185);
PAINT MONO (60 1185);
DISPLAY INVISIBLE (60 1185);
FORCEPROP 1 LASTPIN (50 1175) BN 22
J 2
(62 1183);
DISPLAY 0.680851 (62 1183);
PAINT GREEN (62 1183);
FORCEPROP 2 LAST CDS_LIB standard
J 0
(0 1175);
DISPLAY INVISIBLE (0 1175);
FORCEPROP 1 LAST BODY_TYPE PLUMBING
J 2
(0 1225);
DISPLAY 0.872340 (0 1225);
PAINT GREEN (0 1225);
DISPLAY INVISIBLE (0 1225);
FORCEPROP 1 LAST HDL_TAP TRUE
J 2
(-325 1050);
DISPLAY 0.872340 (-325 1050);
DISPLAY INVISIBLE (-325 1050);
FORCEPROP 1 LAST PATH I39
J 2
(2 1175);
DISPLAY 0.872340 (2 1175);
PAINT GREEN (2 1175);
DISPLAY INVISIBLE (2 1175);
FORCEADD TAP..1
R 2
(0 -525);
FORCEPROP 3 LASTPIN (50 -525) SIG_NAME M_C_CPU0_CLK_DN<1>
J 0
(60 -515);
DISPLAY 0.659574 (60 -515);
PAINT MONO (60 -515);
DISPLAY INVISIBLE (60 -515);
FORCEPROP 1 LASTPIN (50 -525) BN 1
J 2
(62 -517);
DISPLAY 0.680851 (62 -517);
PAINT GREEN (62 -517);
FORCEPROP 2 LAST CDS_LIB standard
J 0
(0 -525);
DISPLAY INVISIBLE (0 -525);
FORCEPROP 1 LAST BODY_TYPE PLUMBING
J 2
(0 -475);
DISPLAY 0.872340 (0 -475);
PAINT GREEN (0 -475);
DISPLAY INVISIBLE (0 -475);
FORCEPROP 1 LAST HDL_TAP TRUE
J 2
(-325 -650);
DISPLAY 0.872340 (-325 -650);
DISPLAY INVISIBLE (-325 -650);
FORCEPROP 1 LAST PATH I4
J 2
(2 -525);
DISPLAY 0.872340 (2 -525);
PAINT GREEN (2 -525);
DISPLAY INVISIBLE (2 -525);
FORCEADD TAP..1
R 2
(0 1275);
FORCEPROP 3 LASTPIN (50 1275) SIG_NAME M_C_CPU0_SB_DQ<24>
J 0
(60 1285);
DISPLAY 0.659574 (60 1285);
PAINT MONO (60 1285);
DISPLAY INVISIBLE (60 1285);
FORCEPROP 1 LASTPIN (50 1275) BN 24
J 2
(62 1283);
DISPLAY 0.680851 (62 1283);
PAINT GREEN (62 1283);
FORCEPROP 2 LAST CDS_LIB standard
J 0
(0 1275);
DISPLAY INVISIBLE (0 1275);
FORCEPROP 1 LAST BODY_TYPE PLUMBING
J 2
(0 1325);
DISPLAY 0.872340 (0 1325);
PAINT GREEN (0 1325);
DISPLAY INVISIBLE (0 1325);
FORCEPROP 1 LAST HDL_TAP TRUE
J 2
(-325 1150);
DISPLAY 0.872340 (-325 1150);
DISPLAY INVISIBLE (-325 1150);
FORCEPROP 1 LAST PATH I40
J 2
(2 1275);
DISPLAY 0.872340 (2 1275);
PAINT GREEN (2 1275);
DISPLAY INVISIBLE (2 1275);
FORCEADD TAP..1
R 2
(0 1225);
FORCEPROP 3 LASTPIN (50 1225) SIG_NAME M_C_CPU0_SB_DQ<23>
J 0
(60 1235);
DISPLAY 0.659574 (60 1235);
PAINT MONO (60 1235);
DISPLAY INVISIBLE (60 1235);
FORCEPROP 1 LASTPIN (50 1225) BN 23
J 2
(62 1233);
DISPLAY 0.680851 (62 1233);
PAINT GREEN (62 1233);
FORCEPROP 2 LAST CDS_LIB standard
J 0
(0 1225);
DISPLAY INVISIBLE (0 1225);
FORCEPROP 1 LAST BODY_TYPE PLUMBING
J 2
(0 1275);
DISPLAY 0.872340 (0 1275);
PAINT GREEN (0 1275);
DISPLAY INVISIBLE (0 1275);
FORCEPROP 1 LAST HDL_TAP TRUE
J 2
(-325 1100);
DISPLAY 0.872340 (-325 1100);
DISPLAY INVISIBLE (-325 1100);
FORCEPROP 1 LAST PATH I41
J 2
(2 1225);
DISPLAY 0.872340 (2 1225);
PAINT GREEN (2 1225);
DISPLAY INVISIBLE (2 1225);
FORCEADD TAP..1
R 2
(0 1325);
FORCEPROP 3 LASTPIN (50 1325) SIG_NAME M_C_CPU0_SB_DQ<25>
J 0
(60 1335);
DISPLAY 0.659574 (60 1335);
PAINT MONO (60 1335);
DISPLAY INVISIBLE (60 1335);
FORCEPROP 1 LASTPIN (50 1325) BN 25
J 2
(62 1333);
DISPLAY 0.680851 (62 1333);
PAINT GREEN (62 1333);
FORCEPROP 2 LAST CDS_LIB standard
J 0
(0 1325);
DISPLAY INVISIBLE (0 1325);
FORCEPROP 1 LAST BODY_TYPE PLUMBING
J 2
(0 1375);
DISPLAY 0.872340 (0 1375);
PAINT GREEN (0 1375);
DISPLAY INVISIBLE (0 1375);
FORCEPROP 1 LAST HDL_TAP TRUE
J 2
(-325 1200);
DISPLAY 0.872340 (-325 1200);
DISPLAY INVISIBLE (-325 1200);
FORCEPROP 1 LAST PATH I42
J 2
(2 1325);
DISPLAY 0.872340 (2 1325);
PAINT GREEN (2 1325);
DISPLAY INVISIBLE (2 1325);
FORCEADD TAP..1
R 2
(0 1375);
FORCEPROP 3 LASTPIN (50 1375) SIG_NAME M_C_CPU0_SB_DQ<26>
J 0
(60 1385);
DISPLAY 0.659574 (60 1385);
PAINT MONO (60 1385);
DISPLAY INVISIBLE (60 1385);
FORCEPROP 1 LASTPIN (50 1375) BN 26
J 2
(62 1383);
DISPLAY 0.680851 (62 1383);
PAINT GREEN (62 1383);
FORCEPROP 2 LAST CDS_LIB standard
J 0
(0 1375);
DISPLAY INVISIBLE (0 1375);
FORCEPROP 1 LAST BODY_TYPE PLUMBING
J 2
(0 1425);
DISPLAY 0.872340 (0 1425);
PAINT GREEN (0 1425);
DISPLAY INVISIBLE (0 1425);
FORCEPROP 1 LAST HDL_TAP TRUE
J 2
(-325 1250);
DISPLAY 0.872340 (-325 1250);
DISPLAY INVISIBLE (-325 1250);
FORCEPROP 1 LAST PATH I43
J 2
(2 1375);
DISPLAY 0.872340 (2 1375);
PAINT GREEN (2 1375);
DISPLAY INVISIBLE (2 1375);
FORCEADD TAP..1
R 2
(0 1425);
FORCEPROP 3 LASTPIN (50 1425) SIG_NAME M_C_CPU0_SB_DQ<27>
J 0
(60 1435);
DISPLAY 0.659574 (60 1435);
PAINT MONO (60 1435);
DISPLAY INVISIBLE (60 1435);
FORCEPROP 1 LASTPIN (50 1425) BN 27
J 2
(62 1433);
DISPLAY 0.680851 (62 1433);
PAINT GREEN (62 1433);
FORCEPROP 2 LAST CDS_LIB standard
J 0
(0 1425);
DISPLAY INVISIBLE (0 1425);
FORCEPROP 1 LAST BODY_TYPE PLUMBING
J 2
(0 1475);
DISPLAY 0.872340 (0 1475);
PAINT GREEN (0 1475);
DISPLAY INVISIBLE (0 1475);
FORCEPROP 1 LAST HDL_TAP TRUE
J 2
(-325 1300);
DISPLAY 0.872340 (-325 1300);
DISPLAY INVISIBLE (-325 1300);
FORCEPROP 1 LAST PATH I44
J 2
(2 1425);
DISPLAY 0.872340 (2 1425);
PAINT GREEN (2 1425);
DISPLAY INVISIBLE (2 1425);
FORCEADD TAP..1
R 2
(0 1475);
FORCEPROP 3 LASTPIN (50 1475) SIG_NAME M_C_CPU0_SB_DQ<28>
J 0
(60 1485);
DISPLAY 0.659574 (60 1485);
PAINT MONO (60 1485);
DISPLAY INVISIBLE (60 1485);
FORCEPROP 1 LASTPIN (50 1475) BN 28
J 2
(62 1483);
DISPLAY 0.680851 (62 1483);
PAINT GREEN (62 1483);
FORCEPROP 2 LAST CDS_LIB standard
J 0
(0 1475);
DISPLAY INVISIBLE (0 1475);
FORCEPROP 1 LAST BODY_TYPE PLUMBING
J 2
(0 1525);
DISPLAY 0.872340 (0 1525);
PAINT GREEN (0 1525);
DISPLAY INVISIBLE (0 1525);
FORCEPROP 1 LAST HDL_TAP TRUE
J 2
(-325 1350);
DISPLAY 0.872340 (-325 1350);
DISPLAY INVISIBLE (-325 1350);
FORCEPROP 1 LAST PATH I45
J 2
(2 1475);
DISPLAY 0.872340 (2 1475);
PAINT GREEN (2 1475);
DISPLAY INVISIBLE (2 1475);
FORCEADD TAP..1
R 2
(0 1525);
FORCEPROP 3 LASTPIN (50 1525) SIG_NAME M_C_CPU0_SB_DQ<29>
J 0
(60 1535);
DISPLAY 0.659574 (60 1535);
PAINT MONO (60 1535);
DISPLAY INVISIBLE (60 1535);
FORCEPROP 1 LASTPIN (50 1525) BN 29
J 2
(62 1533);
DISPLAY 0.680851 (62 1533);
PAINT GREEN (62 1533);
FORCEPROP 2 LAST CDS_LIB standard
J 0
(0 1525);
DISPLAY INVISIBLE (0 1525);
FORCEPROP 1 LAST BODY_TYPE PLUMBING
J 2
(0 1575);
DISPLAY 0.872340 (0 1575);
PAINT GREEN (0 1575);
DISPLAY INVISIBLE (0 1575);
FORCEPROP 1 LAST HDL_TAP TRUE
J 2
(-325 1400);
DISPLAY 0.872340 (-325 1400);
DISPLAY INVISIBLE (-325 1400);
FORCEPROP 1 LAST PATH I46
J 2
(2 1525);
DISPLAY 0.872340 (2 1525);
PAINT GREEN (2 1525);
DISPLAY INVISIBLE (2 1525);
FORCEADD TAP..1
R 2
(0 1625);
FORCEPROP 3 LASTPIN (50 1625) SIG_NAME M_C_CPU0_SB_DQ<31>
J 0
(60 1635);
DISPLAY 0.659574 (60 1635);
PAINT MONO (60 1635);
DISPLAY INVISIBLE (60 1635);
FORCEPROP 1 LASTPIN (50 1625) BN 31
J 2
(62 1633);
DISPLAY 0.680851 (62 1633);
PAINT GREEN (62 1633);
FORCEPROP 2 LAST CDS_LIB standard
J 0
(0 1625);
DISPLAY INVISIBLE (0 1625);
FORCEPROP 1 LAST BODY_TYPE PLUMBING
J 2
(0 1675);
DISPLAY 0.872340 (0 1675);
PAINT GREEN (0 1675);
DISPLAY INVISIBLE (0 1675);
FORCEPROP 1 LAST HDL_TAP TRUE
J 2
(-325 1500);
DISPLAY 0.872340 (-325 1500);
DISPLAY INVISIBLE (-325 1500);
FORCEPROP 1 LAST PATH I47
J 2
(2 1625);
DISPLAY 0.872340 (2 1625);
PAINT GREEN (2 1625);
DISPLAY INVISIBLE (2 1625);
FORCEADD TAP..1
R 2
(0 1575);
FORCEPROP 3 LASTPIN (50 1575) SIG_NAME M_C_CPU0_SB_DQ<30>
J 0
(60 1585);
DISPLAY 0.659574 (60 1585);
PAINT MONO (60 1585);
DISPLAY INVISIBLE (60 1585);
FORCEPROP 1 LASTPIN (50 1575) BN 30
J 2
(62 1583);
DISPLAY 0.680851 (62 1583);
PAINT GREEN (62 1583);
FORCEPROP 2 LAST CDS_LIB standard
J 0
(0 1575);
DISPLAY INVISIBLE (0 1575);
FORCEPROP 1 LAST BODY_TYPE PLUMBING
J 2
(0 1625);
DISPLAY 0.872340 (0 1625);
PAINT GREEN (0 1625);
DISPLAY INVISIBLE (0 1625);
FORCEPROP 1 LAST HDL_TAP TRUE
J 2
(-325 1450);
DISPLAY 0.872340 (-325 1450);
DISPLAY INVISIBLE (-325 1450);
FORCEPROP 1 LAST PATH I48
J 2
(2 1575);
DISPLAY 0.872340 (2 1575);
PAINT GREEN (2 1575);
DISPLAY INVISIBLE (2 1575);
FORCEADD TAP..1
R 2
(0 1675);
FORCEPROP 3 LASTPIN (50 1675) SIG_NAME M_C_CPU0_SA_CB<0>
J 0
(60 1685);
DISPLAY 0.659574 (60 1685);
PAINT MONO (60 1685);
DISPLAY INVISIBLE (60 1685);
FORCEPROP 1 LASTPIN (50 1675) BN 0
J 2
(62 1683);
DISPLAY 0.680851 (62 1683);
PAINT GREEN (62 1683);
FORCEPROP 2 LAST CDS_LIB standard
J 0
(0 1675);
DISPLAY INVISIBLE (0 1675);
FORCEPROP 1 LAST BODY_TYPE PLUMBING
J 2
(0 1725);
DISPLAY 0.872340 (0 1725);
PAINT GREEN (0 1725);
DISPLAY INVISIBLE (0 1725);
FORCEPROP 1 LAST HDL_TAP TRUE
J 2
(-325 1550);
DISPLAY 0.872340 (-325 1550);
DISPLAY INVISIBLE (-325 1550);
FORCEPROP 1 LAST PATH I49
J 2
(2 1675);
DISPLAY 0.872340 (2 1675);
PAINT GREEN (2 1675);
DISPLAY INVISIBLE (2 1675);
FORCEADD TAP..1
R 2
(0 -425);
FORCEPROP 3 LASTPIN (50 -425) SIG_NAME M_C_CPU0_CLK_DP<1>
J 0
(60 -415);
DISPLAY 0.659574 (60 -415);
PAINT MONO (60 -415);
DISPLAY INVISIBLE (60 -415);
FORCEPROP 1 LASTPIN (50 -425) BN 1
J 2
(62 -417);
DISPLAY 0.680851 (62 -417);
PAINT GREEN (62 -417);
FORCEPROP 2 LAST CDS_LIB standard
J 0
(0 -425);
DISPLAY INVISIBLE (0 -425);
FORCEPROP 1 LAST BODY_TYPE PLUMBING
J 2
(0 -375);
DISPLAY 0.872340 (0 -375);
PAINT GREEN (0 -375);
DISPLAY INVISIBLE (0 -375);
FORCEPROP 1 LAST HDL_TAP TRUE
J 2
(-325 -550);
DISPLAY 0.872340 (-325 -550);
DISPLAY INVISIBLE (-325 -550);
FORCEPROP 1 LAST PATH I5
J 2
(2 -425);
DISPLAY 0.872340 (2 -425);
PAINT GREEN (2 -425);
DISPLAY INVISIBLE (2 -425);
FORCEADD OFFPAGE..3
R 2
(-1025 2050);
FORCEPROP 2 LAST $XR1 87 
J 0
(-1394 2050);
DISPLAY 0.638298 (-1394 2050);
PAINT MONO (-1394 2050);
FORCEPROP 2 LAST $XR0 86 
J 0
(-1304 2050);
DISPLAY 0.638298 (-1304 2050);
PAINT MONO (-1304 2050);
FORCEPROP 2 LAST CDS_LIB standard
J 0
(-1025 2050);
DISPLAY INVISIBLE (-1025 2050);
FORCEPROP 1 LAST OFFPAGE TRUE
J 2
(-1350 1925);
DISPLAY 0.872340 (-1350 1925);
DISPLAY INVISIBLE (-1350 1925);
FORCEPROP 1 LAST COMMENT_BODY TRUE
J 2
(-975 1950);
DISPLAY 0.872340 (-975 1950);
PAINT GREEN (-975 1950);
DISPLAY INVISIBLE (-975 1950);
FORCEPROP 2 LAST PATH I50
J 0
(-975 2125);
DISPLAY 1.021277 (-975 2125);
DISPLAY INVISIBLE (-975 2125);
FORCEADD OFFPAGE..3
R 2
(-1025 3650);
FORCEPROP 2 LAST $XR1 87 
J 0
(-1394 3650);
DISPLAY 0.638298 (-1394 3650);
PAINT MONO (-1394 3650);
FORCEPROP 2 LAST $XR0 86 
J 0
(-1304 3650);
DISPLAY 0.638298 (-1304 3650);
PAINT MONO (-1304 3650);
FORCEPROP 2 LAST CDS_LIB standard
J 0
(-1025 3650);
DISPLAY INVISIBLE (-1025 3650);
FORCEPROP 1 LAST OFFPAGE TRUE
J 2
(-1350 3525);
DISPLAY 0.872340 (-1350 3525);
DISPLAY INVISIBLE (-1350 3525);
FORCEPROP 1 LAST COMMENT_BODY TRUE
J 2
(-975 3550);
DISPLAY 0.872340 (-975 3550);
PAINT GREEN (-975 3550);
DISPLAY INVISIBLE (-975 3550);
FORCEPROP 2 LAST PATH I51
J 0
(-975 3725);
DISPLAY 1.021277 (-975 3725);
DISPLAY INVISIBLE (-975 3725);
FORCEADD TAP..1
R 2
(0 1725);
FORCEPROP 3 LASTPIN (50 1725) SIG_NAME M_C_CPU0_SA_CB<1>
J 0
(60 1735);
DISPLAY 0.659574 (60 1735);
PAINT MONO (60 1735);
DISPLAY INVISIBLE (60 1735);
FORCEPROP 1 LASTPIN (50 1725) BN 1
J 2
(62 1733);
DISPLAY 0.680851 (62 1733);
PAINT GREEN (62 1733);
FORCEPROP 2 LAST CDS_LIB standard
J 0
(0 1725);
DISPLAY INVISIBLE (0 1725);
FORCEPROP 1 LAST BODY_TYPE PLUMBING
J 2
(0 1775);
DISPLAY 0.872340 (0 1775);
PAINT GREEN (0 1775);
DISPLAY INVISIBLE (0 1775);
FORCEPROP 1 LAST HDL_TAP TRUE
J 2
(-325 1600);
DISPLAY 0.872340 (-325 1600);
DISPLAY INVISIBLE (-325 1600);
FORCEPROP 1 LAST PATH I52
J 2
(2 1725);
DISPLAY 0.872340 (2 1725);
PAINT GREEN (2 1725);
DISPLAY INVISIBLE (2 1725);
FORCEADD TAP..1
R 2
(0 1775);
FORCEPROP 3 LASTPIN (50 1775) SIG_NAME M_C_CPU0_SA_CB<2>
J 0
(60 1785);
DISPLAY 0.659574 (60 1785);
PAINT MONO (60 1785);
DISPLAY INVISIBLE (60 1785);
FORCEPROP 1 LASTPIN (50 1775) BN 2
J 2
(62 1783);
DISPLAY 0.680851 (62 1783);
PAINT GREEN (62 1783);
FORCEPROP 2 LAST CDS_LIB standard
J 0
(0 1775);
DISPLAY INVISIBLE (0 1775);
FORCEPROP 1 LAST BODY_TYPE PLUMBING
J 2
(0 1825);
DISPLAY 0.872340 (0 1825);
PAINT GREEN (0 1825);
DISPLAY INVISIBLE (0 1825);
FORCEPROP 1 LAST HDL_TAP TRUE
J 2
(-325 1650);
DISPLAY 0.872340 (-325 1650);
DISPLAY INVISIBLE (-325 1650);
FORCEPROP 1 LAST PATH I53
J 2
(2 1775);
DISPLAY 0.872340 (2 1775);
PAINT GREEN (2 1775);
DISPLAY INVISIBLE (2 1775);
FORCEADD TAP..1
R 2
(0 1825);
FORCEPROP 3 LASTPIN (50 1825) SIG_NAME M_C_CPU0_SA_CB<3>
J 0
(60 1835);
DISPLAY 0.659574 (60 1835);
PAINT MONO (60 1835);
DISPLAY INVISIBLE (60 1835);
FORCEPROP 1 LASTPIN (50 1825) BN 3
J 2
(62 1833);
DISPLAY 0.680851 (62 1833);
PAINT GREEN (62 1833);
FORCEPROP 2 LAST CDS_LIB standard
J 0
(0 1825);
DISPLAY INVISIBLE (0 1825);
FORCEPROP 1 LAST BODY_TYPE PLUMBING
J 2
(0 1875);
DISPLAY 0.872340 (0 1875);
PAINT GREEN (0 1875);
DISPLAY INVISIBLE (0 1875);
FORCEPROP 1 LAST HDL_TAP TRUE
J 2
(-325 1700);
DISPLAY 0.872340 (-325 1700);
DISPLAY INVISIBLE (-325 1700);
FORCEPROP 1 LAST PATH I54
J 2
(2 1825);
DISPLAY 0.872340 (2 1825);
PAINT GREEN (2 1825);
DISPLAY INVISIBLE (2 1825);
FORCEADD TAP..1
R 2
(0 1925);
FORCEPROP 3 LASTPIN (50 1925) SIG_NAME M_C_CPU0_SA_CB<5>
J 0
(60 1935);
DISPLAY 0.659574 (60 1935);
PAINT MONO (60 1935);
DISPLAY INVISIBLE (60 1935);
FORCEPROP 1 LASTPIN (50 1925) BN 5
J 2
(62 1933);
DISPLAY 0.680851 (62 1933);
PAINT GREEN (62 1933);
FORCEPROP 2 LAST CDS_LIB standard
J 0
(0 1925);
DISPLAY INVISIBLE (0 1925);
FORCEPROP 1 LAST BODY_TYPE PLUMBING
J 2
(0 1975);
DISPLAY 0.872340 (0 1975);
PAINT GREEN (0 1975);
DISPLAY INVISIBLE (0 1975);
FORCEPROP 1 LAST HDL_TAP TRUE
J 2
(-325 1800);
DISPLAY 0.872340 (-325 1800);
DISPLAY INVISIBLE (-325 1800);
FORCEPROP 1 LAST PATH I55
J 2
(2 1925);
DISPLAY 0.872340 (2 1925);
PAINT GREEN (2 1925);
DISPLAY INVISIBLE (2 1925);
FORCEADD TAP..1
R 2
(0 1875);
FORCEPROP 3 LASTPIN (50 1875) SIG_NAME M_C_CPU0_SA_CB<4>
J 0
(60 1885);
DISPLAY 0.659574 (60 1885);
PAINT MONO (60 1885);
DISPLAY INVISIBLE (60 1885);
FORCEPROP 1 LASTPIN (50 1875) BN 4
J 2
(62 1883);
DISPLAY 0.680851 (62 1883);
PAINT GREEN (62 1883);
FORCEPROP 2 LAST CDS_LIB standard
J 0
(0 1875);
DISPLAY INVISIBLE (0 1875);
FORCEPROP 1 LAST BODY_TYPE PLUMBING
J 2
(0 1925);
DISPLAY 0.872340 (0 1925);
PAINT GREEN (0 1925);
DISPLAY INVISIBLE (0 1925);
FORCEPROP 1 LAST HDL_TAP TRUE
J 2
(-325 1750);
DISPLAY 0.872340 (-325 1750);
DISPLAY INVISIBLE (-325 1750);
FORCEPROP 1 LAST PATH I56
J 2
(2 1875);
DISPLAY 0.872340 (2 1875);
PAINT GREEN (2 1875);
DISPLAY INVISIBLE (2 1875);
FORCEADD TAP..1
R 2
(0 1975);
FORCEPROP 3 LASTPIN (50 1975) SIG_NAME M_C_CPU0_SA_CB<6>
J 0
(60 1985);
DISPLAY 0.659574 (60 1985);
PAINT MONO (60 1985);
DISPLAY INVISIBLE (60 1985);
FORCEPROP 1 LASTPIN (50 1975) BN 6
J 2
(62 1983);
DISPLAY 0.680851 (62 1983);
PAINT GREEN (62 1983);
FORCEPROP 2 LAST CDS_LIB standard
J 0
(0 1975);
DISPLAY INVISIBLE (0 1975);
FORCEPROP 1 LAST BODY_TYPE PLUMBING
J 2
(0 2025);
DISPLAY 0.872340 (0 2025);
PAINT GREEN (0 2025);
DISPLAY INVISIBLE (0 2025);
FORCEPROP 1 LAST HDL_TAP TRUE
J 2
(-325 1850);
DISPLAY 0.872340 (-325 1850);
DISPLAY INVISIBLE (-325 1850);
FORCEPROP 1 LAST PATH I57
J 2
(2 1975);
DISPLAY 0.872340 (2 1975);
PAINT GREEN (2 1975);
DISPLAY INVISIBLE (2 1975);
FORCEADD TAP..1
R 2
(0 2025);
FORCEPROP 3 LASTPIN (50 2025) SIG_NAME M_C_CPU0_SA_CB<7>
J 0
(60 2035);
DISPLAY 0.659574 (60 2035);
PAINT MONO (60 2035);
DISPLAY INVISIBLE (60 2035);
FORCEPROP 1 LASTPIN (50 2025) BN 7
J 2
(62 2033);
DISPLAY 0.680851 (62 2033);
PAINT GREEN (62 2033);
FORCEPROP 2 LAST CDS_LIB standard
J 0
(0 2025);
DISPLAY INVISIBLE (0 2025);
FORCEPROP 1 LAST BODY_TYPE PLUMBING
J 2
(0 2075);
DISPLAY 0.872340 (0 2075);
PAINT GREEN (0 2075);
DISPLAY INVISIBLE (0 2075);
FORCEPROP 1 LAST HDL_TAP TRUE
J 2
(-325 1900);
DISPLAY 0.872340 (-325 1900);
DISPLAY INVISIBLE (-325 1900);
FORCEPROP 1 LAST PATH I58
J 2
(2 2025);
DISPLAY 0.872340 (2 2025);
PAINT GREEN (2 2025);
DISPLAY INVISIBLE (2 2025);
FORCEADD TAP..1
R 2
(0 2075);
FORCEPROP 3 LASTPIN (50 2075) SIG_NAME M_C_CPU0_SA_DQ<0>
J 0
(60 2085);
DISPLAY 0.659574 (60 2085);
PAINT MONO (60 2085);
DISPLAY INVISIBLE (60 2085);
FORCEPROP 1 LASTPIN (50 2075) BN 0
J 2
(62 2083);
DISPLAY 0.680851 (62 2083);
PAINT GREEN (62 2083);
FORCEPROP 2 LAST CDS_LIB standard
J 0
(0 2075);
DISPLAY INVISIBLE (0 2075);
FORCEPROP 1 LAST BODY_TYPE PLUMBING
J 2
(0 2125);
DISPLAY 0.872340 (0 2125);
PAINT GREEN (0 2125);
DISPLAY INVISIBLE (0 2125);
FORCEPROP 1 LAST HDL_TAP TRUE
J 2
(-325 1950);
DISPLAY 0.872340 (-325 1950);
DISPLAY INVISIBLE (-325 1950);
FORCEPROP 1 LAST PATH I59
J 2
(2 2075);
DISPLAY 0.872340 (2 2075);
PAINT GREEN (2 2075);
DISPLAY INVISIBLE (2 2075);
FORCEADD TAP..1
R 2
(0 -475);
FORCEPROP 3 LASTPIN (50 -475) SIG_NAME M_C_CPU0_CLK_DP<0>
J 0
(60 -465);
DISPLAY 0.659574 (60 -465);
PAINT MONO (60 -465);
DISPLAY INVISIBLE (60 -465);
FORCEPROP 1 LASTPIN (50 -475) BN 0
J 2
(62 -467);
DISPLAY 0.680851 (62 -467);
PAINT GREEN (62 -467);
FORCEPROP 2 LAST CDS_LIB standard
J 0
(0 -475);
DISPLAY INVISIBLE (0 -475);
FORCEPROP 1 LAST BODY_TYPE PLUMBING
J 2
(0 -425);
DISPLAY 0.872340 (0 -425);
PAINT GREEN (0 -425);
DISPLAY INVISIBLE (0 -425);
FORCEPROP 1 LAST HDL_TAP TRUE
J 2
(-325 -600);
DISPLAY 0.872340 (-325 -600);
DISPLAY INVISIBLE (-325 -600);
FORCEPROP 1 LAST PATH I6
J 2
(2 -475);
DISPLAY 0.872340 (2 -475);
PAINT GREEN (2 -475);
DISPLAY INVISIBLE (2 -475);
FORCEADD TAP..1
R 2
(0 2125);
FORCEPROP 3 LASTPIN (50 2125) SIG_NAME M_C_CPU0_SA_DQ<1>
J 0
(60 2135);
DISPLAY 0.659574 (60 2135);
PAINT MONO (60 2135);
DISPLAY INVISIBLE (60 2135);
FORCEPROP 1 LASTPIN (50 2125) BN 1
J 2
(62 2133);
DISPLAY 0.680851 (62 2133);
PAINT GREEN (62 2133);
FORCEPROP 2 LAST CDS_LIB standard
J 0
(0 2125);
DISPLAY INVISIBLE (0 2125);
FORCEPROP 1 LAST BODY_TYPE PLUMBING
J 2
(0 2175);
DISPLAY 0.872340 (0 2175);
PAINT GREEN (0 2175);
DISPLAY INVISIBLE (0 2175);
FORCEPROP 1 LAST HDL_TAP TRUE
J 2
(-325 2000);
DISPLAY 0.872340 (-325 2000);
DISPLAY INVISIBLE (-325 2000);
FORCEPROP 1 LAST PATH I60
J 2
(2 2125);
DISPLAY 0.872340 (2 2125);
PAINT GREEN (2 2125);
DISPLAY INVISIBLE (2 2125);
FORCEADD TAP..1
R 2
(0 2175);
FORCEPROP 3 LASTPIN (50 2175) SIG_NAME M_C_CPU0_SA_DQ<2>
J 0
(60 2185);
DISPLAY 0.659574 (60 2185);
PAINT MONO (60 2185);
DISPLAY INVISIBLE (60 2185);
FORCEPROP 1 LASTPIN (50 2175) BN 2
J 2
(62 2183);
DISPLAY 0.680851 (62 2183);
PAINT GREEN (62 2183);
FORCEPROP 2 LAST CDS_LIB standard
J 0
(0 2175);
DISPLAY INVISIBLE (0 2175);
FORCEPROP 1 LAST BODY_TYPE PLUMBING
J 2
(0 2225);
DISPLAY 0.872340 (0 2225);
PAINT GREEN (0 2225);
DISPLAY INVISIBLE (0 2225);
FORCEPROP 1 LAST HDL_TAP TRUE
J 2
(-325 2050);
DISPLAY 0.872340 (-325 2050);
DISPLAY INVISIBLE (-325 2050);
FORCEPROP 1 LAST PATH I61
J 2
(2 2175);
DISPLAY 0.872340 (2 2175);
PAINT GREEN (2 2175);
DISPLAY INVISIBLE (2 2175);
FORCEADD TAP..1
R 2
(0 2225);
FORCEPROP 3 LASTPIN (50 2225) SIG_NAME M_C_CPU0_SA_DQ<3>
J 0
(60 2235);
DISPLAY 0.659574 (60 2235);
PAINT MONO (60 2235);
DISPLAY INVISIBLE (60 2235);
FORCEPROP 1 LASTPIN (50 2225) BN 3
J 2
(62 2233);
DISPLAY 0.680851 (62 2233);
PAINT GREEN (62 2233);
FORCEPROP 2 LAST CDS_LIB standard
J 0
(0 2225);
DISPLAY INVISIBLE (0 2225);
FORCEPROP 1 LAST BODY_TYPE PLUMBING
J 2
(0 2275);
DISPLAY 0.872340 (0 2275);
PAINT GREEN (0 2275);
DISPLAY INVISIBLE (0 2275);
FORCEPROP 1 LAST HDL_TAP TRUE
J 2
(-325 2100);
DISPLAY 0.872340 (-325 2100);
DISPLAY INVISIBLE (-325 2100);
FORCEPROP 1 LAST PATH I62
J 2
(2 2225);
DISPLAY 0.872340 (2 2225);
PAINT GREEN (2 2225);
DISPLAY INVISIBLE (2 2225);
FORCEADD TAP..1
R 2
(0 2275);
FORCEPROP 3 LASTPIN (50 2275) SIG_NAME M_C_CPU0_SA_DQ<4>
J 0
(60 2285);
DISPLAY 0.659574 (60 2285);
PAINT MONO (60 2285);
DISPLAY INVISIBLE (60 2285);
FORCEPROP 1 LASTPIN (50 2275) BN 4
J 2
(62 2283);
DISPLAY 0.680851 (62 2283);
PAINT GREEN (62 2283);
FORCEPROP 2 LAST CDS_LIB standard
J 0
(0 2275);
DISPLAY INVISIBLE (0 2275);
FORCEPROP 1 LAST BODY_TYPE PLUMBING
J 2
(0 2325);
DISPLAY 0.872340 (0 2325);
PAINT GREEN (0 2325);
DISPLAY INVISIBLE (0 2325);
FORCEPROP 1 LAST HDL_TAP TRUE
J 2
(-325 2150);
DISPLAY 0.872340 (-325 2150);
DISPLAY INVISIBLE (-325 2150);
FORCEPROP 1 LAST PATH I63
J 2
(2 2275);
DISPLAY 0.872340 (2 2275);
PAINT GREEN (2 2275);
DISPLAY INVISIBLE (2 2275);
FORCEADD TAP..1
R 2
(0 2325);
FORCEPROP 3 LASTPIN (50 2325) SIG_NAME M_C_CPU0_SA_DQ<5>
J 0
(60 2335);
DISPLAY 0.659574 (60 2335);
PAINT MONO (60 2335);
DISPLAY INVISIBLE (60 2335);
FORCEPROP 1 LASTPIN (50 2325) BN 5
J 2
(62 2333);
DISPLAY 0.680851 (62 2333);
PAINT GREEN (62 2333);
FORCEPROP 2 LAST CDS_LIB standard
J 0
(0 2325);
DISPLAY INVISIBLE (0 2325);
FORCEPROP 1 LAST BODY_TYPE PLUMBING
J 2
(0 2375);
DISPLAY 0.872340 (0 2375);
PAINT GREEN (0 2375);
DISPLAY INVISIBLE (0 2375);
FORCEPROP 1 LAST HDL_TAP TRUE
J 2
(-325 2200);
DISPLAY 0.872340 (-325 2200);
DISPLAY INVISIBLE (-325 2200);
FORCEPROP 1 LAST PATH I64
J 2
(2 2325);
DISPLAY 0.872340 (2 2325);
PAINT GREEN (2 2325);
DISPLAY INVISIBLE (2 2325);
FORCEADD TAP..1
R 2
(0 2425);
FORCEPROP 3 LASTPIN (50 2425) SIG_NAME M_C_CPU0_SA_DQ<7>
J 0
(60 2435);
DISPLAY 0.659574 (60 2435);
PAINT MONO (60 2435);
DISPLAY INVISIBLE (60 2435);
FORCEPROP 1 LASTPIN (50 2425) BN 7
J 2
(62 2433);
DISPLAY 0.680851 (62 2433);
PAINT GREEN (62 2433);
FORCEPROP 2 LAST CDS_LIB standard
J 0
(0 2425);
DISPLAY INVISIBLE (0 2425);
FORCEPROP 1 LAST BODY_TYPE PLUMBING
J 2
(0 2475);
DISPLAY 0.872340 (0 2475);
PAINT GREEN (0 2475);
DISPLAY INVISIBLE (0 2475);
FORCEPROP 1 LAST HDL_TAP TRUE
J 2
(-325 2300);
DISPLAY 0.872340 (-325 2300);
DISPLAY INVISIBLE (-325 2300);
FORCEPROP 1 LAST PATH I65
J 2
(2 2425);
DISPLAY 0.872340 (2 2425);
PAINT GREEN (2 2425);
DISPLAY INVISIBLE (2 2425);
FORCEADD TAP..1
R 2
(0 2375);
FORCEPROP 3 LASTPIN (50 2375) SIG_NAME M_C_CPU0_SA_DQ<6>
J 0
(60 2385);
DISPLAY 0.659574 (60 2385);
PAINT MONO (60 2385);
DISPLAY INVISIBLE (60 2385);
FORCEPROP 1 LASTPIN (50 2375) BN 6
J 2
(62 2383);
DISPLAY 0.680851 (62 2383);
PAINT GREEN (62 2383);
FORCEPROP 2 LAST CDS_LIB standard
J 0
(0 2375);
DISPLAY INVISIBLE (0 2375);
FORCEPROP 1 LAST BODY_TYPE PLUMBING
J 2
(0 2425);
DISPLAY 0.872340 (0 2425);
PAINT GREEN (0 2425);
DISPLAY INVISIBLE (0 2425);
FORCEPROP 1 LAST HDL_TAP TRUE
J 2
(-325 2250);
DISPLAY 0.872340 (-325 2250);
DISPLAY INVISIBLE (-325 2250);
FORCEPROP 1 LAST PATH I66
J 2
(2 2375);
DISPLAY 0.872340 (2 2375);
PAINT GREEN (2 2375);
DISPLAY INVISIBLE (2 2375);
FORCEADD TAP..1
R 2
(0 2475);
FORCEPROP 3 LASTPIN (50 2475) SIG_NAME M_C_CPU0_SA_DQ<8>
J 0
(60 2485);
DISPLAY 0.659574 (60 2485);
PAINT MONO (60 2485);
DISPLAY INVISIBLE (60 2485);
FORCEPROP 1 LASTPIN (50 2475) BN 8
J 2
(62 2483);
DISPLAY 0.680851 (62 2483);
PAINT GREEN (62 2483);
FORCEPROP 2 LAST CDS_LIB standard
J 0
(0 2475);
DISPLAY INVISIBLE (0 2475);
FORCEPROP 1 LAST BODY_TYPE PLUMBING
J 2
(0 2525);
DISPLAY 0.872340 (0 2525);
PAINT GREEN (0 2525);
DISPLAY INVISIBLE (0 2525);
FORCEPROP 1 LAST HDL_TAP TRUE
J 2
(-325 2350);
DISPLAY 0.872340 (-325 2350);
DISPLAY INVISIBLE (-325 2350);
FORCEPROP 1 LAST PATH I67
J 2
(2 2475);
DISPLAY 0.872340 (2 2475);
PAINT GREEN (2 2475);
DISPLAY INVISIBLE (2 2475);
FORCEADD TAP..1
R 2
(0 2525);
FORCEPROP 3 LASTPIN (50 2525) SIG_NAME M_C_CPU0_SA_DQ<9>
J 0
(60 2535);
DISPLAY 0.659574 (60 2535);
PAINT MONO (60 2535);
DISPLAY INVISIBLE (60 2535);
FORCEPROP 1 LASTPIN (50 2525) BN 9
J 2
(62 2533);
DISPLAY 0.680851 (62 2533);
PAINT GREEN (62 2533);
FORCEPROP 2 LAST CDS_LIB standard
J 0
(0 2525);
DISPLAY INVISIBLE (0 2525);
FORCEPROP 1 LAST BODY_TYPE PLUMBING
J 2
(0 2575);
DISPLAY 0.872340 (0 2575);
PAINT GREEN (0 2575);
DISPLAY INVISIBLE (0 2575);
FORCEPROP 1 LAST HDL_TAP TRUE
J 2
(-325 2400);
DISPLAY 0.872340 (-325 2400);
DISPLAY INVISIBLE (-325 2400);
FORCEPROP 1 LAST PATH I68
J 2
(2 2525);
DISPLAY 0.872340 (2 2525);
PAINT GREEN (2 2525);
DISPLAY INVISIBLE (2 2525);
FORCEADD TAP..1
R 2
(0 2575);
FORCEPROP 3 LASTPIN (50 2575) SIG_NAME M_C_CPU0_SA_DQ<10>
J 0
(60 2585);
DISPLAY 0.659574 (60 2585);
PAINT MONO (60 2585);
DISPLAY INVISIBLE (60 2585);
FORCEPROP 1 LASTPIN (50 2575) BN 10
J 2
(62 2583);
DISPLAY 0.680851 (62 2583);
PAINT GREEN (62 2583);
FORCEPROP 2 LAST CDS_LIB standard
J 0
(0 2575);
DISPLAY INVISIBLE (0 2575);
FORCEPROP 1 LAST BODY_TYPE PLUMBING
J 2
(0 2625);
DISPLAY 0.872340 (0 2625);
PAINT GREEN (0 2625);
DISPLAY INVISIBLE (0 2625);
FORCEPROP 1 LAST HDL_TAP TRUE
J 2
(-325 2450);
DISPLAY 0.872340 (-325 2450);
DISPLAY INVISIBLE (-325 2450);
FORCEPROP 1 LAST PATH I69
J 2
(2 2575);
DISPLAY 0.872340 (2 2575);
PAINT GREEN (2 2575);
DISPLAY INVISIBLE (2 2575);
FORCEADD OFFPAGE..3
R 2
(-1025 50);
FORCEPROP 2 LAST $XR1 87 
J 0
(-1394 50);
DISPLAY 0.638298 (-1394 50);
PAINT MONO (-1394 50);
FORCEPROP 2 LAST $XR0 86 
J 0
(-1304 50);
DISPLAY 0.638298 (-1304 50);
PAINT MONO (-1304 50);
FORCEPROP 2 LAST CDS_LIB standard
J 0
(-1025 50);
DISPLAY INVISIBLE (-1025 50);
FORCEPROP 1 LAST OFFPAGE TRUE
J 2
(-1350 -75);
DISPLAY 0.872340 (-1350 -75);
DISPLAY INVISIBLE (-1350 -75);
FORCEPROP 1 LAST COMMENT_BODY TRUE
J 2
(-975 -50);
DISPLAY 0.872340 (-975 -50);
PAINT GREEN (-975 -50);
DISPLAY INVISIBLE (-975 -50);
FORCEPROP 2 LAST PATH I7
J 0
(-975 125);
DISPLAY 1.021277 (-975 125);
DISPLAY INVISIBLE (-975 125);
FORCEADD TAP..1
R 2
(0 2625);
FORCEPROP 3 LASTPIN (50 2625) SIG_NAME M_C_CPU0_SA_DQ<11>
J 0
(60 2635);
DISPLAY 0.659574 (60 2635);
PAINT MONO (60 2635);
DISPLAY INVISIBLE (60 2635);
FORCEPROP 1 LASTPIN (50 2625) BN 11
J 2
(62 2633);
DISPLAY 0.680851 (62 2633);
PAINT GREEN (62 2633);
FORCEPROP 2 LAST CDS_LIB standard
J 0
(0 2625);
DISPLAY INVISIBLE (0 2625);
FORCEPROP 1 LAST BODY_TYPE PLUMBING
J 2
(0 2675);
DISPLAY 0.872340 (0 2675);
PAINT GREEN (0 2675);
DISPLAY INVISIBLE (0 2675);
FORCEPROP 1 LAST HDL_TAP TRUE
J 2
(-325 2500);
DISPLAY 0.872340 (-325 2500);
DISPLAY INVISIBLE (-325 2500);
FORCEPROP 1 LAST PATH I70
J 2
(2 2625);
DISPLAY 0.872340 (2 2625);
PAINT GREEN (2 2625);
DISPLAY INVISIBLE (2 2625);
FORCEADD TAP..1
R 2
(0 2675);
FORCEPROP 3 LASTPIN (50 2675) SIG_NAME M_C_CPU0_SA_DQ<12>
J 0
(60 2685);
DISPLAY 0.659574 (60 2685);
PAINT MONO (60 2685);
DISPLAY INVISIBLE (60 2685);
FORCEPROP 1 LASTPIN (50 2675) BN 12
J 2
(62 2683);
DISPLAY 0.680851 (62 2683);
PAINT GREEN (62 2683);
FORCEPROP 2 LAST CDS_LIB standard
J 0
(0 2675);
DISPLAY INVISIBLE (0 2675);
FORCEPROP 1 LAST BODY_TYPE PLUMBING
J 2
(0 2725);
DISPLAY 0.872340 (0 2725);
PAINT GREEN (0 2725);
DISPLAY INVISIBLE (0 2725);
FORCEPROP 1 LAST HDL_TAP TRUE
J 2
(-325 2550);
DISPLAY 0.872340 (-325 2550);
DISPLAY INVISIBLE (-325 2550);
FORCEPROP 1 LAST PATH I71
J 2
(2 2675);
DISPLAY 0.872340 (2 2675);
PAINT GREEN (2 2675);
DISPLAY INVISIBLE (2 2675);
FORCEADD TAP..1
R 2
(0 2725);
FORCEPROP 3 LASTPIN (50 2725) SIG_NAME M_C_CPU0_SA_DQ<13>
J 0
(60 2735);
DISPLAY 0.659574 (60 2735);
PAINT MONO (60 2735);
DISPLAY INVISIBLE (60 2735);
FORCEPROP 1 LASTPIN (50 2725) BN 13
J 2
(62 2733);
DISPLAY 0.680851 (62 2733);
PAINT GREEN (62 2733);
FORCEPROP 2 LAST CDS_LIB standard
J 0
(0 2725);
DISPLAY INVISIBLE (0 2725);
FORCEPROP 1 LAST BODY_TYPE PLUMBING
J 2
(0 2775);
DISPLAY 0.872340 (0 2775);
PAINT GREEN (0 2775);
DISPLAY INVISIBLE (0 2775);
FORCEPROP 1 LAST HDL_TAP TRUE
J 2
(-325 2600);
DISPLAY 0.872340 (-325 2600);
DISPLAY INVISIBLE (-325 2600);
FORCEPROP 1 LAST PATH I72
J 2
(2 2725);
DISPLAY 0.872340 (2 2725);
PAINT GREEN (2 2725);
DISPLAY INVISIBLE (2 2725);
FORCEADD TAP..1
R 2
(0 2775);
FORCEPROP 3 LASTPIN (50 2775) SIG_NAME M_C_CPU0_SA_DQ<14>
J 0
(60 2785);
DISPLAY 0.659574 (60 2785);
PAINT MONO (60 2785);
DISPLAY INVISIBLE (60 2785);
FORCEPROP 1 LASTPIN (50 2775) BN 14
J 2
(62 2783);
DISPLAY 0.680851 (62 2783);
PAINT GREEN (62 2783);
FORCEPROP 2 LAST CDS_LIB standard
J 0
(0 2775);
DISPLAY INVISIBLE (0 2775);
FORCEPROP 1 LAST BODY_TYPE PLUMBING
J 2
(0 2825);
DISPLAY 0.872340 (0 2825);
PAINT GREEN (0 2825);
DISPLAY INVISIBLE (0 2825);
FORCEPROP 1 LAST HDL_TAP TRUE
J 2
(-325 2650);
DISPLAY 0.872340 (-325 2650);
DISPLAY INVISIBLE (-325 2650);
FORCEPROP 1 LAST PATH I73
J 2
(2 2775);
DISPLAY 0.872340 (2 2775);
PAINT GREEN (2 2775);
DISPLAY INVISIBLE (2 2775);
FORCEADD TAP..1
R 2
(0 2825);
FORCEPROP 3 LASTPIN (50 2825) SIG_NAME M_C_CPU0_SA_DQ<15>
J 0
(60 2835);
DISPLAY 0.659574 (60 2835);
PAINT MONO (60 2835);
DISPLAY INVISIBLE (60 2835);
FORCEPROP 1 LASTPIN (50 2825) BN 15
J 2
(62 2833);
DISPLAY 0.680851 (62 2833);
PAINT GREEN (62 2833);
FORCEPROP 2 LAST CDS_LIB standard
J 0
(0 2825);
DISPLAY INVISIBLE (0 2825);
FORCEPROP 1 LAST BODY_TYPE PLUMBING
J 2
(0 2875);
DISPLAY 0.872340 (0 2875);
PAINT GREEN (0 2875);
DISPLAY INVISIBLE (0 2875);
FORCEPROP 1 LAST HDL_TAP TRUE
J 2
(-325 2700);
DISPLAY 0.872340 (-325 2700);
DISPLAY INVISIBLE (-325 2700);
FORCEPROP 1 LAST PATH I74
J 2
(2 2825);
DISPLAY 0.872340 (2 2825);
PAINT GREEN (2 2825);
DISPLAY INVISIBLE (2 2825);
FORCEADD TAP..1
R 2
(0 2925);
FORCEPROP 3 LASTPIN (50 2925) SIG_NAME M_C_CPU0_SA_DQ<17>
J 0
(60 2935);
DISPLAY 0.659574 (60 2935);
PAINT MONO (60 2935);
DISPLAY INVISIBLE (60 2935);
FORCEPROP 1 LASTPIN (50 2925) BN 17
J 2
(62 2933);
DISPLAY 0.680851 (62 2933);
PAINT GREEN (62 2933);
FORCEPROP 2 LAST CDS_LIB standard
J 0
(0 2925);
DISPLAY INVISIBLE (0 2925);
FORCEPROP 1 LAST BODY_TYPE PLUMBING
J 2
(0 2975);
DISPLAY 0.872340 (0 2975);
PAINT GREEN (0 2975);
DISPLAY INVISIBLE (0 2975);
FORCEPROP 1 LAST HDL_TAP TRUE
J 2
(-325 2800);
DISPLAY 0.872340 (-325 2800);
DISPLAY INVISIBLE (-325 2800);
FORCEPROP 1 LAST PATH I75
J 2
(2 2925);
DISPLAY 0.872340 (2 2925);
PAINT GREEN (2 2925);
DISPLAY INVISIBLE (2 2925);
FORCEADD TAP..1
R 2
(0 2875);
FORCEPROP 3 LASTPIN (50 2875) SIG_NAME M_C_CPU0_SA_DQ<16>
J 0
(60 2885);
DISPLAY 0.659574 (60 2885);
PAINT MONO (60 2885);
DISPLAY INVISIBLE (60 2885);
FORCEPROP 1 LASTPIN (50 2875) BN 16
J 2
(62 2883);
DISPLAY 0.680851 (62 2883);
PAINT GREEN (62 2883);
FORCEPROP 2 LAST CDS_LIB standard
J 0
(0 2875);
DISPLAY INVISIBLE (0 2875);
FORCEPROP 1 LAST BODY_TYPE PLUMBING
J 2
(0 2925);
DISPLAY 0.872340 (0 2925);
PAINT GREEN (0 2925);
DISPLAY INVISIBLE (0 2925);
FORCEPROP 1 LAST HDL_TAP TRUE
J 2
(-325 2750);
DISPLAY 0.872340 (-325 2750);
DISPLAY INVISIBLE (-325 2750);
FORCEPROP 1 LAST PATH I76
J 2
(2 2875);
DISPLAY 0.872340 (2 2875);
PAINT GREEN (2 2875);
DISPLAY INVISIBLE (2 2875);
FORCEADD TAP..1
R 2
(0 2975);
FORCEPROP 3 LASTPIN (50 2975) SIG_NAME M_C_CPU0_SA_DQ<18>
J 0
(60 2985);
DISPLAY 0.659574 (60 2985);
PAINT MONO (60 2985);
DISPLAY INVISIBLE (60 2985);
FORCEPROP 1 LASTPIN (50 2975) BN 18
J 2
(62 2983);
DISPLAY 0.680851 (62 2983);
PAINT GREEN (62 2983);
FORCEPROP 2 LAST CDS_LIB standard
J 0
(0 2975);
DISPLAY INVISIBLE (0 2975);
FORCEPROP 1 LAST BODY_TYPE PLUMBING
J 2
(0 3025);
DISPLAY 0.872340 (0 3025);
PAINT GREEN (0 3025);
DISPLAY INVISIBLE (0 3025);
FORCEPROP 1 LAST HDL_TAP TRUE
J 2
(-325 2850);
DISPLAY 0.872340 (-325 2850);
DISPLAY INVISIBLE (-325 2850);
FORCEPROP 1 LAST PATH I77
J 2
(2 2975);
DISPLAY 0.872340 (2 2975);
PAINT GREEN (2 2975);
DISPLAY INVISIBLE (2 2975);
FORCEADD TAP..1
R 2
(0 3075);
FORCEPROP 3 LASTPIN (50 3075) SIG_NAME M_C_CPU0_SA_DQ<20>
J 0
(60 3085);
DISPLAY 0.659574 (60 3085);
PAINT MONO (60 3085);
DISPLAY INVISIBLE (60 3085);
FORCEPROP 1 LASTPIN (50 3075) BN 20
J 2
(62 3083);
DISPLAY 0.680851 (62 3083);
PAINT GREEN (62 3083);
FORCEPROP 2 LAST CDS_LIB standard
J 0
(0 3075);
DISPLAY INVISIBLE (0 3075);
FORCEPROP 1 LAST BODY_TYPE PLUMBING
J 2
(0 3125);
DISPLAY 0.872340 (0 3125);
PAINT GREEN (0 3125);
DISPLAY INVISIBLE (0 3125);
FORCEPROP 1 LAST HDL_TAP TRUE
J 2
(-325 2950);
DISPLAY 0.872340 (-325 2950);
DISPLAY INVISIBLE (-325 2950);
FORCEPROP 1 LAST PATH I78
J 2
(2 3075);
DISPLAY 0.872340 (2 3075);
PAINT GREEN (2 3075);
DISPLAY INVISIBLE (2 3075);
FORCEADD TAP..1
R 2
(0 3025);
FORCEPROP 3 LASTPIN (50 3025) SIG_NAME M_C_CPU0_SA_DQ<19>
J 0
(60 3035);
DISPLAY 0.659574 (60 3035);
PAINT MONO (60 3035);
DISPLAY INVISIBLE (60 3035);
FORCEPROP 1 LASTPIN (50 3025) BN 19
J 2
(62 3033);
DISPLAY 0.680851 (62 3033);
PAINT GREEN (62 3033);
FORCEPROP 2 LAST CDS_LIB standard
J 0
(0 3025);
DISPLAY INVISIBLE (0 3025);
FORCEPROP 1 LAST BODY_TYPE PLUMBING
J 2
(0 3075);
DISPLAY 0.872340 (0 3075);
PAINT GREEN (0 3075);
DISPLAY INVISIBLE (0 3075);
FORCEPROP 1 LAST HDL_TAP TRUE
J 2
(-325 2900);
DISPLAY 0.872340 (-325 2900);
DISPLAY INVISIBLE (-325 2900);
FORCEPROP 1 LAST PATH I79
J 2
(2 3025);
DISPLAY 0.872340 (2 3025);
PAINT GREEN (2 3025);
DISPLAY INVISIBLE (2 3025);
FORCEADD OFFPAGE..3
R 2
(-1025 1650);
FORCEPROP 2 LAST $XR1 87 
J 0
(-1394 1650);
DISPLAY 0.638298 (-1394 1650);
PAINT MONO (-1394 1650);
FORCEPROP 2 LAST $XR0 86 
J 0
(-1304 1650);
DISPLAY 0.638298 (-1304 1650);
PAINT MONO (-1304 1650);
FORCEPROP 2 LAST CDS_LIB standard
J 0
(-1025 1650);
DISPLAY INVISIBLE (-1025 1650);
FORCEPROP 1 LAST OFFPAGE TRUE
J 2
(-1350 1525);
DISPLAY 0.872340 (-1350 1525);
DISPLAY INVISIBLE (-1350 1525);
FORCEPROP 1 LAST COMMENT_BODY TRUE
J 2
(-975 1550);
DISPLAY 0.872340 (-975 1550);
PAINT GREEN (-975 1550);
DISPLAY INVISIBLE (-975 1550);
FORCEPROP 2 LAST PATH I8
J 0
(-975 1725);
DISPLAY 1.021277 (-975 1725);
DISPLAY INVISIBLE (-975 1725);
FORCEADD TAP..1
R 2
(0 3175);
FORCEPROP 3 LASTPIN (50 3175) SIG_NAME M_C_CPU0_SA_DQ<22>
J 0
(60 3185);
DISPLAY 0.659574 (60 3185);
PAINT MONO (60 3185);
DISPLAY INVISIBLE (60 3185);
FORCEPROP 1 LASTPIN (50 3175) BN 22
J 2
(62 3183);
DISPLAY 0.680851 (62 3183);
PAINT GREEN (62 3183);
FORCEPROP 2 LAST CDS_LIB standard
J 0
(0 3175);
DISPLAY INVISIBLE (0 3175);
FORCEPROP 1 LAST BODY_TYPE PLUMBING
J 2
(0 3225);
DISPLAY 0.872340 (0 3225);
PAINT GREEN (0 3225);
DISPLAY INVISIBLE (0 3225);
FORCEPROP 1 LAST HDL_TAP TRUE
J 2
(-325 3050);
DISPLAY 0.872340 (-325 3050);
DISPLAY INVISIBLE (-325 3050);
FORCEPROP 1 LAST PATH I80
J 2
(2 3175);
DISPLAY 0.872340 (2 3175);
PAINT GREEN (2 3175);
DISPLAY INVISIBLE (2 3175);
FORCEADD TAP..1
R 2
(0 3125);
FORCEPROP 3 LASTPIN (50 3125) SIG_NAME M_C_CPU0_SA_DQ<21>
J 0
(60 3135);
DISPLAY 0.659574 (60 3135);
PAINT MONO (60 3135);
DISPLAY INVISIBLE (60 3135);
FORCEPROP 1 LASTPIN (50 3125) BN 21
J 2
(62 3133);
DISPLAY 0.680851 (62 3133);
PAINT GREEN (62 3133);
FORCEPROP 2 LAST CDS_LIB standard
J 0
(0 3125);
DISPLAY INVISIBLE (0 3125);
FORCEPROP 1 LAST BODY_TYPE PLUMBING
J 2
(0 3175);
DISPLAY 0.872340 (0 3175);
PAINT GREEN (0 3175);
DISPLAY INVISIBLE (0 3175);
FORCEPROP 1 LAST HDL_TAP TRUE
J 2
(-325 3000);
DISPLAY 0.872340 (-325 3000);
DISPLAY INVISIBLE (-325 3000);
FORCEPROP 1 LAST PATH I81
J 2
(2 3125);
DISPLAY 0.872340 (2 3125);
PAINT GREEN (2 3125);
DISPLAY INVISIBLE (2 3125);
FORCEADD TAP..1
R 2
(0 3225);
FORCEPROP 3 LASTPIN (50 3225) SIG_NAME M_C_CPU0_SA_DQ<23>
J 0
(60 3235);
DISPLAY 0.659574 (60 3235);
PAINT MONO (60 3235);
DISPLAY INVISIBLE (60 3235);
FORCEPROP 1 LASTPIN (50 3225) BN 23
J 2
(62 3233);
DISPLAY 0.680851 (62 3233);
PAINT GREEN (62 3233);
FORCEPROP 2 LAST CDS_LIB standard
J 0
(0 3225);
DISPLAY INVISIBLE (0 3225);
FORCEPROP 1 LAST BODY_TYPE PLUMBING
J 2
(0 3275);
DISPLAY 0.872340 (0 3275);
PAINT GREEN (0 3275);
DISPLAY INVISIBLE (0 3275);
FORCEPROP 1 LAST HDL_TAP TRUE
J 2
(-325 3100);
DISPLAY 0.872340 (-325 3100);
DISPLAY INVISIBLE (-325 3100);
FORCEPROP 1 LAST PATH I82
J 2
(2 3225);
DISPLAY 0.872340 (2 3225);
PAINT GREEN (2 3225);
DISPLAY INVISIBLE (2 3225);
FORCEADD TAP..1
R 2
(0 3325);
FORCEPROP 3 LASTPIN (50 3325) SIG_NAME M_C_CPU0_SA_DQ<25>
J 0
(60 3335);
DISPLAY 0.659574 (60 3335);
PAINT MONO (60 3335);
DISPLAY INVISIBLE (60 3335);
FORCEPROP 1 LASTPIN (50 3325) BN 25
J 2
(62 3333);
DISPLAY 0.680851 (62 3333);
PAINT GREEN (62 3333);
FORCEPROP 2 LAST CDS_LIB standard
J 0
(0 3325);
DISPLAY INVISIBLE (0 3325);
FORCEPROP 1 LAST BODY_TYPE PLUMBING
J 2
(0 3375);
DISPLAY 0.872340 (0 3375);
PAINT GREEN (0 3375);
DISPLAY INVISIBLE (0 3375);
FORCEPROP 1 LAST HDL_TAP TRUE
J 2
(-325 3200);
DISPLAY 0.872340 (-325 3200);
DISPLAY INVISIBLE (-325 3200);
FORCEPROP 1 LAST PATH I83
J 2
(2 3325);
DISPLAY 0.872340 (2 3325);
PAINT GREEN (2 3325);
DISPLAY INVISIBLE (2 3325);
FORCEADD TAP..1
R 2
(0 3275);
FORCEPROP 3 LASTPIN (50 3275) SIG_NAME M_C_CPU0_SA_DQ<24>
J 0
(60 3285);
DISPLAY 0.659574 (60 3285);
PAINT MONO (60 3285);
DISPLAY INVISIBLE (60 3285);
FORCEPROP 1 LASTPIN (50 3275) BN 24
J 2
(62 3283);
DISPLAY 0.680851 (62 3283);
PAINT GREEN (62 3283);
FORCEPROP 2 LAST CDS_LIB standard
J 0
(0 3275);
DISPLAY INVISIBLE (0 3275);
FORCEPROP 1 LAST BODY_TYPE PLUMBING
J 2
(0 3325);
DISPLAY 0.872340 (0 3325);
PAINT GREEN (0 3325);
DISPLAY INVISIBLE (0 3325);
FORCEPROP 1 LAST HDL_TAP TRUE
J 2
(-325 3150);
DISPLAY 0.872340 (-325 3150);
DISPLAY INVISIBLE (-325 3150);
FORCEPROP 1 LAST PATH I84
J 2
(2 3275);
DISPLAY 0.872340 (2 3275);
PAINT GREEN (2 3275);
DISPLAY INVISIBLE (2 3275);
FORCEADD TAP..1
R 2
(0 3425);
FORCEPROP 3 LASTPIN (50 3425) SIG_NAME M_C_CPU0_SA_DQ<27>
J 0
(60 3435);
DISPLAY 0.659574 (60 3435);
PAINT MONO (60 3435);
DISPLAY INVISIBLE (60 3435);
FORCEPROP 1 LASTPIN (50 3425) BN 27
J 2
(62 3433);
DISPLAY 0.680851 (62 3433);
PAINT GREEN (62 3433);
FORCEPROP 2 LAST CDS_LIB standard
J 0
(0 3425);
DISPLAY INVISIBLE (0 3425);
FORCEPROP 1 LAST BODY_TYPE PLUMBING
J 2
(0 3475);
DISPLAY 0.872340 (0 3475);
PAINT GREEN (0 3475);
DISPLAY INVISIBLE (0 3475);
FORCEPROP 1 LAST HDL_TAP TRUE
J 2
(-325 3300);
DISPLAY 0.872340 (-325 3300);
DISPLAY INVISIBLE (-325 3300);
FORCEPROP 1 LAST PATH I85
J 2
(2 3425);
DISPLAY 0.872340 (2 3425);
PAINT GREEN (2 3425);
DISPLAY INVISIBLE (2 3425);
FORCEADD TAP..1
R 2
(0 3375);
FORCEPROP 3 LASTPIN (50 3375) SIG_NAME M_C_CPU0_SA_DQ<26>
J 0
(60 3385);
DISPLAY 0.659574 (60 3385);
PAINT MONO (60 3385);
DISPLAY INVISIBLE (60 3385);
FORCEPROP 1 LASTPIN (50 3375) BN 26
J 2
(62 3383);
DISPLAY 0.680851 (62 3383);
PAINT GREEN (62 3383);
FORCEPROP 2 LAST CDS_LIB standard
J 0
(0 3375);
DISPLAY INVISIBLE (0 3375);
FORCEPROP 1 LAST BODY_TYPE PLUMBING
J 2
(0 3425);
DISPLAY 0.872340 (0 3425);
PAINT GREEN (0 3425);
DISPLAY INVISIBLE (0 3425);
FORCEPROP 1 LAST HDL_TAP TRUE
J 2
(-325 3250);
DISPLAY 0.872340 (-325 3250);
DISPLAY INVISIBLE (-325 3250);
FORCEPROP 1 LAST PATH I86
J 2
(2 3375);
DISPLAY 0.872340 (2 3375);
PAINT GREEN (2 3375);
DISPLAY INVISIBLE (2 3375);
FORCEADD TAP..1
R 2
(0 3475);
FORCEPROP 3 LASTPIN (50 3475) SIG_NAME M_C_CPU0_SA_DQ<28>
J 0
(60 3485);
DISPLAY 0.659574 (60 3485);
PAINT MONO (60 3485);
DISPLAY INVISIBLE (60 3485);
FORCEPROP 1 LASTPIN (50 3475) BN 28
J 2
(62 3483);
DISPLAY 0.680851 (62 3483);
PAINT GREEN (62 3483);
FORCEPROP 2 LAST CDS_LIB standard
J 0
(0 3475);
DISPLAY INVISIBLE (0 3475);
FORCEPROP 1 LAST BODY_TYPE PLUMBING
J 2
(0 3525);
DISPLAY 0.872340 (0 3525);
PAINT GREEN (0 3525);
DISPLAY INVISIBLE (0 3525);
FORCEPROP 1 LAST HDL_TAP TRUE
J 2
(-325 3350);
DISPLAY 0.872340 (-325 3350);
DISPLAY INVISIBLE (-325 3350);
FORCEPROP 1 LAST PATH I87
J 2
(2 3475);
DISPLAY 0.872340 (2 3475);
PAINT GREEN (2 3475);
DISPLAY INVISIBLE (2 3475);
FORCEADD TAP..1
R 2
(0 3525);
FORCEPROP 3 LASTPIN (50 3525) SIG_NAME M_C_CPU0_SA_DQ<29>
J 0
(60 3535);
DISPLAY 0.659574 (60 3535);
PAINT MONO (60 3535);
DISPLAY INVISIBLE (60 3535);
FORCEPROP 1 LASTPIN (50 3525) BN 29
J 2
(62 3533);
DISPLAY 0.680851 (62 3533);
PAINT GREEN (62 3533);
FORCEPROP 2 LAST CDS_LIB standard
J 0
(0 3525);
DISPLAY INVISIBLE (0 3525);
FORCEPROP 1 LAST BODY_TYPE PLUMBING
J 2
(0 3575);
DISPLAY 0.872340 (0 3575);
PAINT GREEN (0 3575);
DISPLAY INVISIBLE (0 3575);
FORCEPROP 1 LAST HDL_TAP TRUE
J 2
(-325 3400);
DISPLAY 0.872340 (-325 3400);
DISPLAY INVISIBLE (-325 3400);
FORCEPROP 1 LAST PATH I88
J 2
(2 3525);
DISPLAY 0.872340 (2 3525);
PAINT GREEN (2 3525);
DISPLAY INVISIBLE (2 3525);
FORCEADD TAP..1
R 2
(0 3575);
FORCEPROP 3 LASTPIN (50 3575) SIG_NAME M_C_CPU0_SA_DQ<30>
J 0
(60 3585);
DISPLAY 0.659574 (60 3585);
PAINT MONO (60 3585);
DISPLAY INVISIBLE (60 3585);
FORCEPROP 1 LASTPIN (50 3575) BN 30
J 2
(62 3583);
DISPLAY 0.680851 (62 3583);
PAINT GREEN (62 3583);
FORCEPROP 2 LAST CDS_LIB standard
J 0
(0 3575);
DISPLAY INVISIBLE (0 3575);
FORCEPROP 1 LAST BODY_TYPE PLUMBING
J 2
(0 3625);
DISPLAY 0.872340 (0 3625);
PAINT GREEN (0 3625);
DISPLAY INVISIBLE (0 3625);
FORCEPROP 1 LAST HDL_TAP TRUE
J 2
(-325 3450);
DISPLAY 0.872340 (-325 3450);
DISPLAY INVISIBLE (-325 3450);
FORCEPROP 1 LAST PATH I89
J 2
(2 3575);
DISPLAY 0.872340 (2 3575);
PAINT GREEN (2 3575);
DISPLAY INVISIBLE (2 3575);
FORCEADD TAP..1
R 2
(0 -275);
FORCEPROP 3 LASTPIN (50 -275) SIG_NAME M_C_CPU0_SB_CB<1>
J 0
(60 -265);
DISPLAY 0.659574 (60 -265);
PAINT MONO (60 -265);
DISPLAY INVISIBLE (60 -265);
FORCEPROP 1 LASTPIN (50 -275) BN 1
J 2
(62 -267);
DISPLAY 0.680851 (62 -267);
PAINT GREEN (62 -267);
FORCEPROP 2 LAST CDS_LIB standard
J 0
(0 -275);
DISPLAY INVISIBLE (0 -275);
FORCEPROP 1 LAST BODY_TYPE PLUMBING
J 2
(0 -225);
DISPLAY 0.872340 (0 -225);
PAINT GREEN (0 -225);
DISPLAY INVISIBLE (0 -225);
FORCEPROP 1 LAST HDL_TAP TRUE
J 2
(-325 -400);
DISPLAY 0.872340 (-325 -400);
DISPLAY INVISIBLE (-325 -400);
FORCEPROP 1 LAST PATH I9
J 2
(2 -275);
DISPLAY 0.872340 (2 -275);
PAINT GREEN (2 -275);
DISPLAY INVISIBLE (2 -275);
FORCEADD TAP..1
R 2
(0 3625);
FORCEPROP 3 LASTPIN (50 3625) SIG_NAME M_C_CPU0_SA_DQ<31>
J 0
(60 3635);
DISPLAY 0.659574 (60 3635);
PAINT MONO (60 3635);
DISPLAY INVISIBLE (60 3635);
FORCEPROP 1 LASTPIN (50 3625) BN 31
J 2
(62 3633);
DISPLAY 0.680851 (62 3633);
PAINT GREEN (62 3633);
FORCEPROP 2 LAST CDS_LIB standard
J 0
(0 3625);
DISPLAY INVISIBLE (0 3625);
FORCEPROP 1 LAST BODY_TYPE PLUMBING
J 2
(0 3675);
DISPLAY 0.872340 (0 3675);
PAINT GREEN (0 3675);
DISPLAY INVISIBLE (0 3675);
FORCEPROP 1 LAST HDL_TAP TRUE
J 2
(-325 3500);
DISPLAY 0.872340 (-325 3500);
DISPLAY INVISIBLE (-325 3500);
FORCEPROP 1 LAST PATH I90
J 2
(2 3625);
DISPLAY 0.872340 (2 3625);
PAINT GREEN (2 3625);
DISPLAY INVISIBLE (2 3625);
FORCEADD OFFPAGE..4
(4525 -575);
FORCEPROP 2 LAST $XR1 87 
J 0
(4801 -575);
DISPLAY 0.638298 (4801 -575);
PAINT MONO (4801 -575);
FORCEPROP 2 LAST $XR0 86 
J 0
(4711 -575);
DISPLAY 0.638298 (4711 -575);
PAINT MONO (4711 -575);
FORCEPROP 2 LAST CDS_LIB standard
J 0
(4525 -575);
PAINT MONO (4525 -575);
DISPLAY INVISIBLE (4525 -575);
FORCEPROP 1 LAST OFFPAGE TRUE
J 0
(4850 -700);
DISPLAY 1.170213 (4850 -700);
PAINT GREEN (4850 -700);
DISPLAY INVISIBLE (4850 -700);
FORCEPROP 1 LAST COMMENT_BODY TRUE
J 0
(4500 -675);
DISPLAY 1.170213 (4500 -675);
PAINT GREEN (4500 -675);
DISPLAY INVISIBLE (4500 -675);
FORCEPROP 2 LAST PATH I92
J 0
(4700 -500);
DISPLAY 1.021277 (4700 -500);
DISPLAY INVISIBLE (4700 -500);
FORCEADD OFFPAGE..4
(4525 -475);
FORCEPROP 2 LAST $XR0 86 
J 0
(4711 -475);
DISPLAY 0.638298 (4711 -475);
PAINT MONO (4711 -475);
FORCEPROP 2 LAST CDS_LIB standard
J 0
(4525 -475);
PAINT MONO (4525 -475);
DISPLAY INVISIBLE (4525 -475);
FORCEPROP 1 LAST OFFPAGE TRUE
J 0
(4850 -600);
DISPLAY 1.170213 (4850 -600);
PAINT GREEN (4850 -600);
DISPLAY INVISIBLE (4850 -600);
FORCEPROP 1 LAST COMMENT_BODY TRUE
J 0
(4500 -575);
DISPLAY 1.170213 (4500 -575);
PAINT GREEN (4500 -575);
DISPLAY INVISIBLE (4500 -575);
FORCEPROP 2 LAST PATH I93
J 0
(4700 -400);
DISPLAY 1.021277 (4700 -400);
DISPLAY INVISIBLE (4700 -400);
FORCEADD OFFPAGE..4
(4525 -425);
FORCEPROP 2 LAST $XR0 87 
J 0
(4711 -425);
DISPLAY 0.638298 (4711 -425);
PAINT MONO (4711 -425);
FORCEPROP 2 LAST CDS_LIB standard
J 0
(4525 -425);
PAINT MONO (4525 -425);
DISPLAY INVISIBLE (4525 -425);
FORCEPROP 1 LAST OFFPAGE TRUE
J 0
(4850 -550);
DISPLAY 1.170213 (4850 -550);
PAINT GREEN (4850 -550);
DISPLAY INVISIBLE (4850 -550);
FORCEPROP 1 LAST COMMENT_BODY TRUE
J 0
(4500 -525);
DISPLAY 1.170213 (4500 -525);
PAINT GREEN (4500 -525);
DISPLAY INVISIBLE (4500 -525);
FORCEPROP 2 LAST PATH I94
J 0
(4700 -350);
DISPLAY 1.021277 (4700 -350);
DISPLAY INVISIBLE (4700 -350);
FORCEADD OFFPAGE..4
(4525 -325);
FORCEPROP 2 LAST $XR0 86 
J 0
(4711 -325);
DISPLAY 0.638298 (4711 -325);
PAINT MONO (4711 -325);
FORCEPROP 2 LAST CDS_LIB standard
J 0
(4525 -325);
PAINT MONO (4525 -325);
DISPLAY INVISIBLE (4525 -325);
FORCEPROP 1 LAST OFFPAGE TRUE
J 0
(4850 -450);
DISPLAY 1.170213 (4850 -450);
PAINT GREEN (4850 -450);
DISPLAY INVISIBLE (4850 -450);
FORCEPROP 1 LAST COMMENT_BODY TRUE
J 0
(4500 -425);
DISPLAY 1.170213 (4500 -425);
PAINT GREEN (4500 -425);
DISPLAY INVISIBLE (4500 -425);
FORCEPROP 2 LAST PATH I95
J 0
(4700 -250);
DISPLAY 1.021277 (4700 -250);
DISPLAY INVISIBLE (4700 -250);
FORCEADD TAP..1
(3425 -125);
FORCEPROP 3 LASTPIN (3375 -125) SIG_NAME M_C_CPU0_SB_CS_N<0>
J 0
(3385 -115);
DISPLAY 0.659574 (3385 -115);
PAINT MONO (3385 -115);
DISPLAY INVISIBLE (3385 -115);
FORCEPROP 1 LASTPIN (3375 -125) BN 0
J 0
(3363 -117);
DISPLAY 0.680851 (3363 -117);
PAINT GREEN (3363 -117);
FORCEPROP 2 LAST CDS_LIB standard
J 0
(3425 -125);
DISPLAY INVISIBLE (3425 -125);
FORCEPROP 1 LAST BODY_TYPE PLUMBING
J 0
(3425 -75);
DISPLAY 0.872340 (3425 -75);
PAINT GREEN (3425 -75);
DISPLAY INVISIBLE (3425 -75);
FORCEPROP 1 LAST HDL_TAP TRUE
J 0
(3750 -250);
DISPLAY 0.872340 (3750 -250);
DISPLAY INVISIBLE (3750 -250);
FORCEPROP 1 LAST PATH I96
J 0
(3423 -125);
DISPLAY 0.872340 (3423 -125);
PAINT GREEN (3423 -125);
DISPLAY INVISIBLE (3423 -125);
FORCEADD TAP..1
(3425 -75);
FORCEPROP 3 LASTPIN (3375 -75) SIG_NAME M_C_CPU0_SB_CS_N<1>
J 0
(3385 -65);
DISPLAY 0.659574 (3385 -65);
PAINT MONO (3385 -65);
DISPLAY INVISIBLE (3385 -65);
FORCEPROP 1 LASTPIN (3375 -75) BN 1
J 0
(3363 -67);
DISPLAY 0.680851 (3363 -67);
PAINT GREEN (3363 -67);
FORCEPROP 2 LAST CDS_LIB standard
J 0
(3425 -75);
DISPLAY INVISIBLE (3425 -75);
FORCEPROP 1 LAST BODY_TYPE PLUMBING
J 0
(3425 -25);
DISPLAY 0.872340 (3425 -25);
PAINT GREEN (3425 -25);
DISPLAY INVISIBLE (3425 -25);
FORCEPROP 1 LAST HDL_TAP TRUE
J 0
(3750 -200);
DISPLAY 0.872340 (3750 -200);
DISPLAY INVISIBLE (3750 -200);
FORCEPROP 1 LAST PATH I97
J 0
(3423 -75);
DISPLAY 0.872340 (3423 -75);
PAINT GREEN (3423 -75);
DISPLAY INVISIBLE (3423 -75);
FORCEADD TAP..1
(3425 25);
FORCEPROP 3 LASTPIN (3375 25) SIG_NAME M_C_CPU0_SB_CS_N<3>
J 0
(3385 35);
DISPLAY 0.659574 (3385 35);
PAINT MONO (3385 35);
DISPLAY INVISIBLE (3385 35);
FORCEPROP 1 LASTPIN (3375 25) BN 3
J 0
(3363 33);
DISPLAY 0.680851 (3363 33);
PAINT GREEN (3363 33);
FORCEPROP 2 LAST CDS_LIB standard
J 0
(3425 25);
DISPLAY INVISIBLE (3425 25);
FORCEPROP 1 LAST BODY_TYPE PLUMBING
J 0
(3425 75);
DISPLAY 0.872340 (3425 75);
PAINT GREEN (3425 75);
DISPLAY INVISIBLE (3425 75);
FORCEPROP 1 LAST HDL_TAP TRUE
J 0
(3750 -100);
DISPLAY 0.872340 (3750 -100);
DISPLAY INVISIBLE (3750 -100);
FORCEPROP 1 LAST PATH I98
J 0
(3423 25);
DISPLAY 0.872340 (3423 25);
PAINT GREEN (3423 25);
DISPLAY INVISIBLE (3423 25);
FORCEADD TAP..1
(3425 -25);
FORCEPROP 3 LASTPIN (3375 -25) SIG_NAME M_C_CPU0_SB_CS_N<2>
J 0
(3385 -15);
DISPLAY 0.659574 (3385 -15);
PAINT MONO (3385 -15);
DISPLAY INVISIBLE (3385 -15);
FORCEPROP 1 LASTPIN (3375 -25) BN 2
J 0
(3363 -17);
DISPLAY 0.680851 (3363 -17);
PAINT GREEN (3363 -17);
FORCEPROP 2 LAST CDS_LIB standard
J 0
(3425 -25);
DISPLAY INVISIBLE (3425 -25);
FORCEPROP 1 LAST BODY_TYPE PLUMBING
J 0
(3425 25);
DISPLAY 0.872340 (3425 25);
PAINT GREEN (3425 25);
DISPLAY INVISIBLE (3425 25);
FORCEPROP 1 LAST HDL_TAP TRUE
J 0
(3750 -150);
DISPLAY 0.872340 (3750 -150);
DISPLAY INVISIBLE (3750 -150);
FORCEPROP 1 LAST PATH I99
J 0
(3423 -25);
DISPLAY 0.872340 (3423 -25);
PAINT GREEN (3423 -25);
DISPLAY INVISIBLE (3423 -25);
FORCEADD QUANTA_TITLE_BLOCK_C..1
(6350 -1875);
FORCEPROP 0 LAST CDS_CON_LAST_MODIFIED Fri Aug 25 14:00:08 2023
J 0
(4465 -1860);
PAINT MONO (4465 -1860);
DISPLAY INVISIBLE (4465 -1860);
FORCEPROP 1 LAST CUSTOM_TXT_CDS <CON_LAST_MODIFIED>
J 0
(4465 -1860);
DISPLAY 0.978723 (4465 -1860);
FORCEPROP 2 LAST CUSTOM_TXT_CDS <XR_PAGE_TITLE>
J 0
(-1540 3375);
DISPLAY 0.638298 (-1540 3375);
PAINT PINK (-1540 3375);
DISPLAY INVISIBLE (-1540 3375);
FORCEPROP 2 LAST CUSTOM_TXT_CDS <Q_NUMBER>
J 0
(4947 -1772);
DISPLAY 1.212766 (4947 -1772);
FORCEPROP 2 LAST CUSTOM_TXT_CDS <CON_PAGE_NUM> OF <CON_TOTAL_PAGES>
J 0
(5904 -1857);
DISPLAY 0.978723 (5904 -1857);
FORCEPROP 2 LAST CUSTOM_TXT_CDS <Q_PROJ>
J 0
(3968 -1773);
DISPLAY 1.212766 (3968 -1773);
FORCEPROP 2 LAST CUSTOM_TXT_CDS <Q_REV>
J 0
(6166 -1772);
DISPLAY 1.212766 (6166 -1772);
FORCEPROP 1 LAST CUSTOM_TXT_CDS <NAME_2>
J 0
(3175 -1825);
FORCEPROP 1 LAST CUSTOM_TXT_CDS <NAME_1>
J 0
(3175 -1700);
FORCEPROP 1 LAST Q_TITLE SPR CPU0 - DDR CH C (10 OF 30)
J 0
(-3016 -1849);
DISPLAY 1.957447 (-3016 -1849);
PAINT GREEN (-3016 -1849);
FORCEPROP 1 LAST Q_DEPT 
J 1
(2587 -1826);
DISPLAY 1.957447 (2587 -1826);
PAINT GREEN (2587 -1826);
FORCEPROP 2 LAST PAGE_BORDER TRUE
J 0
(-1540 3375);
DISPLAY 0.638298 (-1540 3375);
PAINT PINK (-1540 3375);
DISPLAY INVISIBLE (-1540 3375);
FORCEPROP 1 LAST CDS_LMAN_SYM_OUTLINE -9475,6775,100,-125
J 0
(6350 -1875);
DISPLAY 0.468085 (6350 -1875);
PAINT GREEN (6350 -1875);
DISPLAY INVISIBLE (6350 -1875);
FORCEPROP 2 LAST CDS_LIB pure_quanta
J 0
(6350 -1875);
PAINT MONO (6350 -1875);
DISPLAY INVISIBLE (6350 -1875);
FORCEPROP 2 LAST CDS_XR_PAGE_TITLE CR-22 : @S9S_MB_2U_LIB.S9S_MB_2U(SCH_1):PAGE22
J 0
(-1540 3375);
DISPLAY 0.638298 (-1540 3375);
PAINT PINK (-1540 3375);
DISPLAY INVISIBLE (-1540 3375);
FORCEPROP 1 LAST COMMENT_BODY TRUE
J 0
(6362 -1888);
DISPLAY 0.978723 (6362 -1888);
PAINT GREEN (6362 -1888);
DISPLAY INVISIBLE (6362 -1888);
WIRE 17 -1 (3475 1300)(3475 1350);
WIRE 17 -1 (3475 1250)(3475 1300);
WIRE 17 -1 (3475 1350)(4475 1350);
FORCEPROP 2 LAST SIG_NAME M_C_CPU0_SA_CA<6:0>
J 0
(3615 1360);
DISPLAY 0.680851 (3615 1360);
PAINT WHITE (3615 1360);
WIRE 17 -1 (3475 1200)(3475 1250);
WIRE 17 -1 (3475 1150)(3475 1200);
WIRE 17 -1 (3475 1100)(3475 1150);
WIRE 17 -1 (3475 1050)(3475 1100);
WIRE 17 -1 (3475 300)(3475 350);
WIRE 17 -1 (3475 250)(3475 300);
WIRE 17 -1 (3475 350)(4475 350);
FORCEPROP 2 LAST SIG_NAME M_C_CPU0_SA_CS_N<3:0>
J 0
(3615 360);
DISPLAY 0.680851 (3615 360);
PAINT WHITE (3615 360);
WIRE 17 -1 (3475 200)(3475 250);
WIRE 17 -1 (3475 3050)(3475 3100);
WIRE 17 -1 (3475 3000)(3475 3050);
WIRE 17 -1 (3475 3100)(4475 3100);
FORCEPROP 2 LAST SIG_NAME M_C_CPU0_SA_DQS_DN<9:0>
J 0
(3615 3110);
DISPLAY 0.680851 (3615 3110);
PAINT WHITE (3615 3110);
WIRE 17 -1 (3475 2950)(3475 3000);
WIRE 17 -1 (3475 2900)(3475 2950);
WIRE 17 -1 (3475 2850)(3475 2900);
WIRE 17 -1 (3475 2800)(3475 2850);
WIRE 17 -1 (3475 2750)(3475 2800);
WIRE 17 -1 (3475 2700)(3475 2750);
WIRE 17 -1 (3475 2650)(3475 2700);
WIRE 17 -1 (3475 3600)(3475 3650);
WIRE 17 -1 (3475 3550)(3475 3600);
WIRE 17 -1 (3475 3650)(4475 3650);
FORCEPROP 2 LAST SIG_NAME M_C_CPU0_SA_DQS_DP<9:0>
J 0
(3615 3660);
DISPLAY 0.680851 (3615 3660);
PAINT WHITE (3615 3660);
WIRE 17 -1 (3475 3500)(3475 3550);
WIRE 17 -1 (3475 3450)(3475 3500);
WIRE 17 -1 (3475 3400)(3475 3450);
WIRE 17 -1 (3475 3350)(3475 3400);
WIRE 17 -1 (3475 3300)(3475 3350);
WIRE 17 -1 (3475 3250)(3475 3300);
WIRE 17 -1 (3475 3200)(3475 3250);
WIRE 17 -1 (3475 800)(3475 850);
WIRE 17 -1 (3475 750)(3475 800);
WIRE 17 -1 (3475 850)(4475 850);
FORCEPROP 2 LAST SIG_NAME M_C_CPU0_SB_CA<6:0>
J 0
(3615 860);
DISPLAY 0.680851 (3615 860);
PAINT WHITE (3615 860);
WIRE 17 -1 (3475 700)(3475 750);
WIRE 17 -1 (3475 650)(3475 700);
WIRE 17 -1 (3475 600)(3475 650);
WIRE 17 -1 (3475 550)(3475 600);
WIRE 17 -1 (3475 0)(3475 50);
WIRE 17 -1 (3475 -50)(3475 0);
WIRE 17 -1 (3475 50)(4475 50);
FORCEPROP 2 LAST SIG_NAME M_C_CPU0_SB_CS_N<3:0>
J 0
(3615 60);
DISPLAY 0.680851 (3615 60);
PAINT WHITE (3615 60);
WIRE 17 -1 (3475 -100)(3475 -50);
WIRE 17 -1 (3475 1900)(3475 1950);
WIRE 17 -1 (3475 1850)(3475 1900);
WIRE 17 -1 (3475 1950)(4475 1950);
FORCEPROP 2 LAST SIG_NAME M_C_CPU0_SB_DQS_DN<9:0>
J 0
(3615 1960);
DISPLAY 0.680851 (3615 1960);
PAINT WHITE (3615 1960);
WIRE 17 -1 (3475 1800)(3475 1850);
WIRE 17 -1 (3475 1750)(3475 1800);
WIRE 17 -1 (3475 1700)(3475 1750);
WIRE 17 -1 (3475 1650)(3475 1700);
WIRE 17 -1 (3475 1600)(3475 1650);
WIRE 17 -1 (3475 1550)(3475 1600);
WIRE 17 -1 (3475 1500)(3475 1550);
WIRE 17 -1 (3475 2450)(3475 2500);
WIRE 17 -1 (3475 2400)(3475 2450);
WIRE 17 -1 (3475 2500)(4475 2500);
FORCEPROP 2 LAST SIG_NAME M_C_CPU0_SB_DQS_DP<9:0>
J 0
(3615 2510);
DISPLAY 0.680851 (3615 2510);
PAINT WHITE (3615 2510);
WIRE 17 -1 (3475 2350)(3475 2400);
WIRE 17 -1 (3475 2300)(3475 2350);
WIRE 17 -1 (3475 2250)(3475 2300);
WIRE 17 -1 (3475 2200)(3475 2250);
WIRE 17 -1 (3475 2150)(3475 2200);
WIRE 17 -1 (3475 2100)(3475 2150);
WIRE 17 -1 (3475 2050)(3475 2100);
WIRE 17 -1 (-50 -300)(-50 -250);
WIRE 17 -1 (-50 -250)(-50 -200);
WIRE 17 -1 (-50 -200)(-50 -150);
WIRE 17 -1 (-50 -150)(-50 -100);
WIRE 17 -1 (-50 -100)(-50 -50);
WIRE 17 -1 (-50 -50)(-50 0);
WIRE 17 -1 (-50 0)(-50 50);
WIRE 17 -1 (-975 50)(-50 50);
FORCEPROP 2 LAST SIG_NAME M_C_CPU0_SB_CB<7:0>
J 0
(-835 60);
DISPLAY 0.680851 (-835 60);
PAINT WHITE (-835 60);
WIRE 17 -1 (-50 100)(-50 150);
WIRE 17 -1 (-50 150)(-50 200);
WIRE 17 -1 (-50 200)(-50 250);
WIRE 17 -1 (-50 250)(-50 300);
WIRE 17 -1 (-50 300)(-50 350);
WIRE 17 -1 (-50 350)(-50 400);
WIRE 17 -1 (-50 400)(-50 450);
WIRE 17 -1 (-50 450)(-50 500);
WIRE 17 -1 (-50 500)(-50 550);
WIRE 17 -1 (-50 550)(-50 600);
WIRE 17 -1 (-50 600)(-50 650);
WIRE 17 -1 (-50 650)(-50 700);
WIRE 17 -1 (-50 700)(-50 750);
WIRE 17 -1 (-50 750)(-50 800);
WIRE 17 -1 (-50 800)(-50 850);
WIRE 17 -1 (-50 850)(-50 900);
WIRE 17 -1 (-50 900)(-50 950);
WIRE 17 -1 (-50 950)(-50 1000);
WIRE 17 -1 (-50 1000)(-50 1050);
WIRE 17 -1 (-50 1050)(-50 1100);
WIRE 17 -1 (-50 1100)(-50 1150);
WIRE 17 -1 (-50 1150)(-50 1200);
WIRE 17 -1 (-50 1200)(-50 1250);
WIRE 17 -1 (-50 1250)(-50 1300);
WIRE 17 -1 (-50 1300)(-50 1350);
WIRE 17 -1 (-50 1350)(-50 1400);
WIRE 17 -1 (-50 1400)(-50 1450);
WIRE 17 -1 (-50 1450)(-50 1500);
WIRE 17 -1 (-50 1500)(-50 1550);
WIRE 17 -1 (-50 1550)(-50 1600);
WIRE 17 -1 (-50 1600)(-50 1650);
WIRE 17 -1 (-975 1650)(-50 1650);
FORCEPROP 2 LAST SIG_NAME M_C_CPU0_SB_DQ<31:0>
J 0
(-835 1660);
DISPLAY 0.680851 (-835 1660);
PAINT WHITE (-835 1660);
WIRE 17 -1 (-50 1700)(-50 1750);
WIRE 17 -1 (-50 1750)(-50 1800);
WIRE 17 -1 (-50 1800)(-50 1850);
WIRE 17 -1 (-50 1850)(-50 1900);
WIRE 17 -1 (-50 1900)(-50 1950);
WIRE 17 -1 (-50 1950)(-50 2000);
WIRE 17 -1 (-50 2000)(-50 2050);
WIRE 17 -1 (-975 2050)(-50 2050);
FORCEPROP 2 LAST SIG_NAME M_C_CPU0_SA_CB<7:0>
J 0
(-835 2060);
DISPLAY 0.680851 (-835 2060);
PAINT WHITE (-835 2060);
WIRE 17 -1 (-50 2100)(-50 2150);
WIRE 17 -1 (-50 2150)(-50 2200);
WIRE 17 -1 (-50 2200)(-50 2250);
WIRE 17 -1 (-50 2250)(-50 2300);
WIRE 17 -1 (-50 2300)(-50 2350);
WIRE 17 -1 (-50 2350)(-50 2400);
WIRE 17 -1 (-50 2400)(-50 2450);
WIRE 17 -1 (-50 2450)(-50 2500);
WIRE 17 -1 (-50 2500)(-50 2550);
WIRE 17 -1 (-50 2550)(-50 2600);
WIRE 17 -1 (-50 2600)(-50 2650);
WIRE 17 -1 (-50 2650)(-50 2700);
WIRE 17 -1 (-50 2700)(-50 2750);
WIRE 17 -1 (-50 2750)(-50 2800);
WIRE 17 -1 (-50 2800)(-50 2850);
WIRE 17 -1 (-50 2850)(-50 2900);
WIRE 17 -1 (-50 2900)(-50 2950);
WIRE 17 -1 (-50 2950)(-50 3000);
WIRE 17 -1 (-50 3000)(-50 3050);
WIRE 17 -1 (-50 3050)(-50 3100);
WIRE 17 -1 (-50 3100)(-50 3150);
WIRE 17 -1 (-50 3150)(-50 3200);
WIRE 17 -1 (-50 3200)(-50 3250);
WIRE 17 -1 (-50 3250)(-50 3300);
WIRE 17 -1 (-50 3300)(-50 3350);
WIRE 17 -1 (-50 3350)(-50 3400);
WIRE 17 -1 (-50 3400)(-50 3450);
WIRE 17 -1 (-50 3450)(-50 3500);
WIRE 17 -1 (-50 3500)(-50 3550);
WIRE 17 -1 (-50 3550)(-50 3600);
WIRE 17 -1 (-50 3600)(-50 3650);
WIRE 17 -1 (-975 3650)(-50 3650);
FORCEPROP 2 LAST SIG_NAME M_C_CPU0_SA_DQ<31:0>
J 0
(-835 3660);
DISPLAY 0.680851 (-835 3660);
PAINT WHITE (-835 3660);
WIRE 17 -1 (-50 -450)(-50 -400);
WIRE 17 -1 (-975 -400)(-50 -400);
FORCEPROP 2 LAST SIG_NAME M_C_CPU0_CLK_DP<1:0>
J 0
(-835 -390);
DISPLAY 0.680851 (-835 -390);
PAINT WHITE (-835 -390);
WIRE 17 -1 (-50 -550)(-50 -500);
WIRE 17 -1 (-975 -500)(-50 -500);
FORCEPROP 2 LAST SIG_NAME M_C_CPU0_CLK_DN<1:0>
J 0
(-835 -490);
DISPLAY 0.680851 (-835 -490);
PAINT WHITE (-835 -490);
WIRE 16 -1 (50 -525)(500 -525);
WIRE 16 -1 (50 -575)(500 -575);
WIRE 16 -1 (50 -425)(500 -425);
WIRE 16 -1 (50 -475)(500 -475);
WIRE 16 -1 (50 3625)(500 3625);
WIRE 16 -1 (50 3575)(500 3575);
WIRE 16 -1 (50 3525)(500 3525);
WIRE 16 -1 (50 3475)(500 3475);
WIRE 16 -1 (50 3425)(500 3425);
WIRE 16 -1 (50 3375)(500 3375);
WIRE 16 -1 (50 3325)(500 3325);
WIRE 16 -1 (50 3275)(500 3275);
WIRE 16 -1 (50 3225)(500 3225);
WIRE 16 -1 (50 3175)(500 3175);
WIRE 16 -1 (50 3125)(500 3125);
WIRE 16 -1 (50 3075)(500 3075);
WIRE 16 -1 (50 3025)(500 3025);
WIRE 16 -1 (50 2975)(500 2975);
WIRE 16 -1 (50 2925)(500 2925);
WIRE 16 -1 (50 2875)(500 2875);
WIRE 16 -1 (50 2825)(500 2825);
WIRE 16 -1 (50 2775)(500 2775);
WIRE 16 -1 (50 2725)(500 2725);
WIRE 16 -1 (50 2675)(500 2675);
WIRE 16 -1 (50 2625)(500 2625);
WIRE 16 -1 (50 2575)(500 2575);
WIRE 16 -1 (50 2525)(500 2525);
WIRE 16 -1 (50 2475)(500 2475);
WIRE 16 -1 (50 2425)(500 2425);
WIRE 16 -1 (50 2375)(500 2375);
WIRE 16 -1 (50 2325)(500 2325);
WIRE 16 -1 (50 2275)(500 2275);
WIRE 16 -1 (50 2225)(500 2225);
WIRE 16 -1 (50 2175)(500 2175);
WIRE 16 -1 (50 2125)(500 2125);
WIRE 16 -1 (50 2075)(500 2075);
WIRE 16 -1 (50 2025)(500 2025);
WIRE 16 -1 (50 1975)(500 1975);
WIRE 16 -1 (50 1925)(500 1925);
WIRE 16 -1 (50 1875)(500 1875);
WIRE 16 -1 (50 1825)(500 1825);
WIRE 16 -1 (50 1775)(500 1775);
WIRE 16 -1 (50 1725)(500 1725);
WIRE 16 -1 (50 1675)(500 1675);
WIRE 16 -1 (50 1625)(500 1625);
WIRE 16 -1 (50 1575)(500 1575);
WIRE 16 -1 (50 1525)(500 1525);
WIRE 16 -1 (50 1475)(500 1475);
WIRE 16 -1 (50 1425)(500 1425);
WIRE 16 -1 (50 1375)(500 1375);
WIRE 16 -1 (50 1325)(500 1325);
WIRE 16 -1 (50 1275)(500 1275);
WIRE 16 -1 (50 1225)(500 1225);
WIRE 16 -1 (50 1175)(500 1175);
WIRE 16 -1 (50 1125)(500 1125);
WIRE 16 -1 (50 1075)(500 1075);
WIRE 16 -1 (50 1025)(500 1025);
WIRE 16 -1 (50 975)(500 975);
WIRE 16 -1 (50 925)(500 925);
WIRE 16 -1 (50 875)(500 875);
WIRE 16 -1 (50 825)(500 825);
WIRE 16 -1 (50 775)(500 775);
WIRE 16 -1 (50 725)(500 725);
WIRE 16 -1 (50 675)(500 675);
WIRE 16 -1 (50 625)(500 625);
WIRE 16 -1 (50 575)(500 575);
WIRE 16 -1 (50 525)(500 525);
WIRE 16 -1 (50 475)(500 475);
WIRE 16 -1 (50 425)(500 425);
WIRE 16 -1 (50 375)(500 375);
WIRE 16 -1 (50 325)(500 325);
WIRE 16 -1 (50 275)(500 275);
WIRE 16 -1 (50 225)(500 225);
WIRE 16 -1 (50 175)(500 175);
WIRE 16 -1 (50 125)(500 125);
WIRE 16 -1 (50 75)(500 75);
WIRE 16 -1 (50 25)(500 25);
WIRE 16 -1 (50 -25)(500 -25);
WIRE 16 -1 (50 -75)(500 -75);
WIRE 16 -1 (50 -125)(500 -125);
WIRE 16 -1 (50 -175)(500 -175);
WIRE 16 -1 (50 -225)(500 -225);
WIRE 16 -1 (50 -275)(500 -275);
WIRE 16 -1 (50 -325)(500 -325);
WIRE 16 -1 (4475 475)(2950 475);
FORCEPROP 2 LAST SIG_NAME M_C_CPU0_SB_PAR
J 0
(3584 484);
DISPLAY 0.680851 (3584 484);
PAINT WHITE (3584 484);
WIRE 16 -1 (2950 2025)(3375 2025);
WIRE 16 -1 (2950 2075)(3375 2075);
WIRE 16 -1 (2950 2125)(3375 2125);
WIRE 16 -1 (2950 2175)(3375 2175);
WIRE 16 -1 (2950 2225)(3375 2225);
WIRE 16 -1 (2950 2275)(3375 2275);
WIRE 16 -1 (2950 2325)(3375 2325);
WIRE 16 -1 (2950 2375)(3375 2375);
WIRE 16 -1 (2950 2425)(3375 2425);
WIRE 16 -1 (2950 2475)(3375 2475);
WIRE 16 -1 (2950 1475)(3375 1475);
WIRE 16 -1 (2950 1525)(3375 1525);
WIRE 16 -1 (2950 1575)(3375 1575);
WIRE 16 -1 (2950 1625)(3375 1625);
WIRE 16 -1 (2950 1675)(3375 1675);
WIRE 16 -1 (2950 1725)(3375 1725);
WIRE 16 -1 (2950 1775)(3375 1775);
WIRE 16 -1 (2950 1825)(3375 1825);
WIRE 16 -1 (2950 1875)(3375 1875);
WIRE 16 -1 (2950 1925)(3375 1925);
WIRE 16 -1 (2950 -125)(3375 -125);
WIRE 16 -1 (2950 -75)(3375 -75);
WIRE 16 -1 (2950 -25)(3375 -25);
WIRE 16 -1 (2950 25)(3375 25);
WIRE 16 -1 (2950 525)(3375 525);
WIRE 16 -1 (2950 575)(3375 575);
WIRE 16 -1 (2950 625)(3375 625);
WIRE 16 -1 (2950 675)(3375 675);
WIRE 16 -1 (2950 725)(3375 725);
WIRE 16 -1 (2950 775)(3375 775);
WIRE 16 -1 (2950 825)(3375 825);
WIRE 16 -1 (4475 975)(2950 975);
FORCEPROP 2 LAST SIG_NAME M_C_CPU0_SA_PAR
J 0
(3584 984);
DISPLAY 0.680851 (3584 984);
PAINT WHITE (3584 984);
WIRE 16 -1 (2950 3175)(3375 3175);
WIRE 16 -1 (2950 3225)(3375 3225);
WIRE 16 -1 (2950 3275)(3375 3275);
WIRE 16 -1 (2950 3325)(3375 3325);
WIRE 16 -1 (2950 3375)(3375 3375);
WIRE 16 -1 (2950 3425)(3375 3425);
WIRE 16 -1 (2950 3475)(3375 3475);
WIRE 16 -1 (2950 3525)(3375 3525);
WIRE 16 -1 (2950 3575)(3375 3575);
WIRE 16 -1 (2950 3625)(3375 3625);
WIRE 16 -1 (2950 2625)(3375 2625);
WIRE 16 -1 (2950 2675)(3375 2675);
WIRE 16 -1 (2950 2725)(3375 2725);
WIRE 16 -1 (2950 2775)(3375 2775);
WIRE 16 -1 (2950 2825)(3375 2825);
WIRE 16 -1 (2950 2875)(3375 2875);
WIRE 16 -1 (2950 2925)(3375 2925);
WIRE 16 -1 (2950 2975)(3375 2975);
WIRE 16 -1 (2950 3025)(3375 3025);
WIRE 16 -1 (2950 3075)(3375 3075);
WIRE 16 -1 (2950 175)(3375 175);
WIRE 16 -1 (2950 225)(3375 225);
WIRE 16 -1 (2950 275)(3375 275);
WIRE 16 -1 (2950 325)(3375 325);
WIRE 16 -1 (2950 1025)(3375 1025);
WIRE 16 -1 (2950 1075)(3375 1075);
WIRE 16 -1 (2950 1125)(3375 1125);
WIRE 16 -1 (2950 1175)(3375 1175);
WIRE 16 -1 (2950 1225)(3375 1225);
WIRE 16 -1 (2950 1275)(3375 1275);
WIRE 16 -1 (2950 1325)(3375 1325);
WIRE 16 -1 (4475 -475)(2950 -475);
FORCEPROP 2 LAST SIG_NAME M_C_CPU0_SB_RSP<0>
J 0
(3584 -466);
DISPLAY 0.680851 (3584 -466);
PAINT WHITE (3584 -466);
WIRE 16 -1 (4475 -425)(2950 -425);
FORCEPROP 2 LAST SIG_NAME M_C_CPU0_SB_RSP<1>
J 0
(3584 -416);
DISPLAY 0.680851 (3584 -416);
PAINT WHITE (3584 -416);
WIRE 16 -1 (4475 -325)(2950 -325);
FORCEPROP 2 LAST SIG_NAME M_C_CPU0_SA_RSP<0>
J 0
(3584 -316);
DISPLAY 0.680851 (3584 -316);
PAINT WHITE (3584 -316);
WIRE 16 -1 (4475 -275)(2950 -275);
FORCEPROP 2 LAST SIG_NAME M_C_CPU0_SA_RSP<1>
J 0
(3584 -266);
DISPLAY 0.680851 (3584 -266);
PAINT WHITE (3584 -266);
WIRE 16 -1 (4475 -575)(2950 -575);
FORCEPROP 2 LAST SIG_NAME M_C_CPU0_ALERT_N
J 0
(3584 -566);
DISPLAY 0.680851 (3584 -566);
PAINT WHITE (3584 -566);
QUIT
